FILE_TYPE = MACRO_DRAWING;
SET COLOR_WIRE YELLOW;
SET COLOR_PROP ORANGE;
SET COLOR_DOT WHITE;
SET COLOR_ARC YELLOW;
SET COLOR_BODY GREEN;
SET COLOR_NOTE PURPLE;
SET PROP_DISPLAY VALUE;
SET PAGE_NUMBER P23;
FORCEADD OFFPAGE..2
R 2
(-1050 -225);
FORCEPROP 2 LAST $XR1 89 
J 0
(-1394 -225);
DISPLAY 0.638298 (-1394 -225);
PAINT MONO (-1394 -225);
FORCEPROP 2 LAST $XR0 88 
J 0
(-1304 -225);
DISPLAY 0.638298 (-1304 -225);
PAINT MONO (-1304 -225);
FORCEPROP 2 LAST CDS_LIB standard
J 0
(-1050 -225);
PAINT MONO (-1050 -225);
DISPLAY INVISIBLE (-1050 -225);
FORCEPROP 1 LAST OFFPAGE TRUE
J 2
(-1375 -350);
DISPLAY 0.872340 (-1375 -350);
DISPLAY INVISIBLE (-1375 -350);
FORCEPROP 1 LAST COMMENT_BODY TRUE
J 2
(-1005 -320);
DISPLAY 0.872340 (-1005 -320);
PAINT GREEN (-1005 -320);
DISPLAY INVISIBLE (-1005 -320);
FORCEPROP 2 LAST PATH I1
J 0
(-1000 -150);
DISPLAY 1.021277 (-1000 -150);
DISPLAY INVISIBLE (-1000 -150);
FORCEADD TAP..1
R 2
(-25 0);
FORCEPROP 3 LASTPIN (25 0) SIG_NAME M_D_CPU0_SB_CB<1>
J 0
(35 10);
DISPLAY 0.659574 (35 10);
PAINT MONO (35 10);
DISPLAY INVISIBLE (35 10);
FORCEPROP 1 LASTPIN (25 0) BN 1
J 2
(37 8);
DISPLAY 0.680851 (37 8);
PAINT GREEN (37 8);
FORCEPROP 2 LAST CDS_LIB standard
J 0
(-25 0);
DISPLAY INVISIBLE (-25 0);
FORCEPROP 1 LAST BODY_TYPE PLUMBING
J 2
(-25 50);
DISPLAY 0.872340 (-25 50);
PAINT GREEN (-25 50);
DISPLAY INVISIBLE (-25 50);
FORCEPROP 1 LAST HDL_TAP TRUE
J 2
(-350 -125);
DISPLAY 0.872340 (-350 -125);
DISPLAY INVISIBLE (-350 -125);
FORCEPROP 1 LAST PATH I10
J 2
(-23 0);
DISPLAY 0.872340 (-23 0);
PAINT GREEN (-23 0);
DISPLAY INVISIBLE (-23 0);
FORCEADD TAP..1
(3400 300);
FORCEPROP 3 LASTPIN (3350 300) SIG_NAME M_D_CPU0_SB_CS_N<3>
J 0
(3360 310);
DISPLAY 0.659574 (3360 310);
PAINT MONO (3360 310);
DISPLAY INVISIBLE (3360 310);
FORCEPROP 1 LASTPIN (3350 300) BN 3
J 0
(3338 308);
DISPLAY 0.680851 (3338 308);
PAINT GREEN (3338 308);
FORCEPROP 2 LAST CDS_LIB standard
J 0
(3400 300);
DISPLAY INVISIBLE (3400 300);
FORCEPROP 1 LAST BODY_TYPE PLUMBING
J 0
(3400 350);
DISPLAY 0.872340 (3400 350);
PAINT GREEN (3400 350);
DISPLAY INVISIBLE (3400 350);
FORCEPROP 1 LAST HDL_TAP TRUE
J 0
(3725 175);
DISPLAY 0.872340 (3725 175);
DISPLAY INVISIBLE (3725 175);
FORCEPROP 1 LAST PATH I100
J 0
(3398 300);
DISPLAY 0.872340 (3398 300);
PAINT GREEN (3398 300);
DISPLAY INVISIBLE (3398 300);
FORCEADD TAP..1
(3400 500);
FORCEPROP 3 LASTPIN (3350 500) SIG_NAME M_D_CPU0_SA_CS_N<1>
J 0
(3360 510);
DISPLAY 0.659574 (3360 510);
PAINT MONO (3360 510);
DISPLAY INVISIBLE (3360 510);
FORCEPROP 1 LASTPIN (3350 500) BN 1
J 0
(3338 508);
DISPLAY 0.680851 (3338 508);
PAINT GREEN (3338 508);
FORCEPROP 2 LAST CDS_LIB standard
J 0
(3400 500);
DISPLAY INVISIBLE (3400 500);
FORCEPROP 1 LAST BODY_TYPE PLUMBING
J 0
(3400 550);
DISPLAY 0.872340 (3400 550);
PAINT GREEN (3400 550);
DISPLAY INVISIBLE (3400 550);
FORCEPROP 1 LAST HDL_TAP TRUE
J 0
(3725 375);
DISPLAY 0.872340 (3725 375);
DISPLAY INVISIBLE (3725 375);
FORCEPROP 1 LAST PATH I101
J 0
(3398 500);
DISPLAY 0.872340 (3398 500);
PAINT GREEN (3398 500);
DISPLAY INVISIBLE (3398 500);
FORCEADD TAP..1
(3400 450);
FORCEPROP 3 LASTPIN (3350 450) SIG_NAME M_D_CPU0_SA_CS_N<0>
J 0
(3360 460);
DISPLAY 0.659574 (3360 460);
PAINT MONO (3360 460);
DISPLAY INVISIBLE (3360 460);
FORCEPROP 1 LASTPIN (3350 450) BN 0
J 0
(3338 458);
DISPLAY 0.680851 (3338 458);
PAINT GREEN (3338 458);
FORCEPROP 2 LAST CDS_LIB standard
J 0
(3400 450);
DISPLAY INVISIBLE (3400 450);
FORCEPROP 1 LAST BODY_TYPE PLUMBING
J 0
(3400 500);
DISPLAY 0.872340 (3400 500);
PAINT GREEN (3400 500);
DISPLAY INVISIBLE (3400 500);
FORCEPROP 1 LAST HDL_TAP TRUE
J 0
(3725 325);
DISPLAY 0.872340 (3725 325);
DISPLAY INVISIBLE (3725 325);
FORCEPROP 1 LAST PATH I102
J 0
(3398 450);
DISPLAY 0.872340 (3398 450);
PAINT GREEN (3398 450);
DISPLAY INVISIBLE (3398 450);
FORCEADD TAP..1
(3400 600);
FORCEPROP 3 LASTPIN (3350 600) SIG_NAME M_D_CPU0_SA_CS_N<3>
J 0
(3360 610);
DISPLAY 0.659574 (3360 610);
PAINT MONO (3360 610);
DISPLAY INVISIBLE (3360 610);
FORCEPROP 1 LASTPIN (3350 600) BN 3
J 0
(3338 608);
DISPLAY 0.680851 (3338 608);
PAINT GREEN (3338 608);
FORCEPROP 2 LAST CDS_LIB standard
J 0
(3400 600);
DISPLAY INVISIBLE (3400 600);
FORCEPROP 1 LAST BODY_TYPE PLUMBING
J 0
(3400 650);
DISPLAY 0.872340 (3400 650);
PAINT GREEN (3400 650);
DISPLAY INVISIBLE (3400 650);
FORCEPROP 1 LAST HDL_TAP TRUE
J 0
(3725 475);
DISPLAY 0.872340 (3725 475);
DISPLAY INVISIBLE (3725 475);
FORCEPROP 1 LAST PATH I103
J 0
(3398 600);
DISPLAY 0.872340 (3398 600);
PAINT GREEN (3398 600);
DISPLAY INVISIBLE (3398 600);
FORCEADD TAP..1
(3400 550);
FORCEPROP 3 LASTPIN (3350 550) SIG_NAME M_D_CPU0_SA_CS_N<2>
J 0
(3360 560);
DISPLAY 0.659574 (3360 560);
PAINT MONO (3360 560);
DISPLAY INVISIBLE (3360 560);
FORCEPROP 1 LASTPIN (3350 550) BN 2
J 0
(3338 558);
DISPLAY 0.680851 (3338 558);
PAINT GREEN (3338 558);
FORCEPROP 2 LAST CDS_LIB standard
J 0
(3400 550);
DISPLAY INVISIBLE (3400 550);
FORCEPROP 1 LAST BODY_TYPE PLUMBING
J 0
(3400 600);
DISPLAY 0.872340 (3400 600);
PAINT GREEN (3400 600);
DISPLAY INVISIBLE (3400 600);
FORCEPROP 1 LAST HDL_TAP TRUE
J 0
(3725 425);
DISPLAY 0.872340 (3725 425);
DISPLAY INVISIBLE (3725 425);
FORCEPROP 1 LAST PATH I104
J 0
(3398 550);
DISPLAY 0.872340 (3398 550);
PAINT GREEN (3398 550);
DISPLAY INVISIBLE (3398 550);
FORCEADD TAP..1
(3400 800);
FORCEPROP 3 LASTPIN (3350 800) SIG_NAME M_D_CPU0_SB_CA<0>
J 0
(3360 810);
DISPLAY 0.659574 (3360 810);
PAINT MONO (3360 810);
DISPLAY INVISIBLE (3360 810);
FORCEPROP 1 LASTPIN (3350 800) BN 0
J 0
(3338 808);
DISPLAY 0.680851 (3338 808);
PAINT GREEN (3338 808);
FORCEPROP 2 LAST CDS_LIB standard
J 0
(3400 800);
DISPLAY INVISIBLE (3400 800);
FORCEPROP 1 LAST BODY_TYPE PLUMBING
J 0
(3400 850);
DISPLAY 0.872340 (3400 850);
PAINT GREEN (3400 850);
DISPLAY INVISIBLE (3400 850);
FORCEPROP 1 LAST HDL_TAP TRUE
J 0
(3725 675);
DISPLAY 0.872340 (3725 675);
DISPLAY INVISIBLE (3725 675);
FORCEPROP 1 LAST PATH I105
J 0
(3398 800);
DISPLAY 0.872340 (3398 800);
PAINT GREEN (3398 800);
DISPLAY INVISIBLE (3398 800);
FORCEADD TAP..1
(3400 850);
FORCEPROP 3 LASTPIN (3350 850) SIG_NAME M_D_CPU0_SB_CA<1>
J 0
(3360 860);
DISPLAY 0.659574 (3360 860);
PAINT MONO (3360 860);
DISPLAY INVISIBLE (3360 860);
FORCEPROP 1 LASTPIN (3350 850) BN 1
J 0
(3338 858);
DISPLAY 0.680851 (3338 858);
PAINT GREEN (3338 858);
FORCEPROP 2 LAST CDS_LIB standard
J 0
(3400 850);
DISPLAY INVISIBLE (3400 850);
FORCEPROP 1 LAST BODY_TYPE PLUMBING
J 0
(3400 900);
DISPLAY 0.872340 (3400 900);
PAINT GREEN (3400 900);
DISPLAY INVISIBLE (3400 900);
FORCEPROP 1 LAST HDL_TAP TRUE
J 0
(3725 725);
DISPLAY 0.872340 (3725 725);
DISPLAY INVISIBLE (3725 725);
FORCEPROP 1 LAST PATH I106
J 0
(3398 850);
DISPLAY 0.872340 (3398 850);
PAINT GREEN (3398 850);
DISPLAY INVISIBLE (3398 850);
FORCEADD TAP..1
(3400 900);
FORCEPROP 3 LASTPIN (3350 900) SIG_NAME M_D_CPU0_SB_CA<2>
J 0
(3360 910);
DISPLAY 0.659574 (3360 910);
PAINT MONO (3360 910);
DISPLAY INVISIBLE (3360 910);
FORCEPROP 1 LASTPIN (3350 900) BN 2
J 0
(3338 908);
DISPLAY 0.680851 (3338 908);
PAINT GREEN (3338 908);
FORCEPROP 2 LAST CDS_LIB standard
J 0
(3400 900);
DISPLAY INVISIBLE (3400 900);
FORCEPROP 1 LAST BODY_TYPE PLUMBING
J 0
(3400 950);
DISPLAY 0.872340 (3400 950);
PAINT GREEN (3400 950);
DISPLAY INVISIBLE (3400 950);
FORCEPROP 1 LAST HDL_TAP TRUE
J 0
(3725 775);
DISPLAY 0.872340 (3725 775);
DISPLAY INVISIBLE (3725 775);
FORCEPROP 1 LAST PATH I107
J 0
(3398 900);
DISPLAY 0.872340 (3398 900);
PAINT GREEN (3398 900);
DISPLAY INVISIBLE (3398 900);
FORCEADD TAP..1
(3400 1000);
FORCEPROP 3 LASTPIN (3350 1000) SIG_NAME M_D_CPU0_SB_CA<4>
J 0
(3360 1010);
DISPLAY 0.659574 (3360 1010);
PAINT MONO (3360 1010);
DISPLAY INVISIBLE (3360 1010);
FORCEPROP 1 LASTPIN (3350 1000) BN 4
J 0
(3338 1008);
DISPLAY 0.680851 (3338 1008);
PAINT GREEN (3338 1008);
FORCEPROP 2 LAST CDS_LIB standard
J 0
(3400 1000);
DISPLAY INVISIBLE (3400 1000);
FORCEPROP 1 LAST BODY_TYPE PLUMBING
J 0
(3400 1050);
DISPLAY 0.872340 (3400 1050);
PAINT GREEN (3400 1050);
DISPLAY INVISIBLE (3400 1050);
FORCEPROP 1 LAST HDL_TAP TRUE
J 0
(3725 875);
DISPLAY 0.872340 (3725 875);
DISPLAY INVISIBLE (3725 875);
FORCEPROP 1 LAST PATH I108
J 0
(3398 1000);
DISPLAY 0.872340 (3398 1000);
PAINT GREEN (3398 1000);
DISPLAY INVISIBLE (3398 1000);
FORCEADD TAP..1
(3400 950);
FORCEPROP 3 LASTPIN (3350 950) SIG_NAME M_D_CPU0_SB_CA<3>
J 0
(3360 960);
DISPLAY 0.659574 (3360 960);
PAINT MONO (3360 960);
DISPLAY INVISIBLE (3360 960);
FORCEPROP 1 LASTPIN (3350 950) BN 3
J 0
(3338 958);
DISPLAY 0.680851 (3338 958);
PAINT GREEN (3338 958);
FORCEPROP 2 LAST CDS_LIB standard
J 0
(3400 950);
DISPLAY INVISIBLE (3400 950);
FORCEPROP 1 LAST BODY_TYPE PLUMBING
J 0
(3400 1000);
DISPLAY 0.872340 (3400 1000);
PAINT GREEN (3400 1000);
DISPLAY INVISIBLE (3400 1000);
FORCEPROP 1 LAST HDL_TAP TRUE
J 0
(3725 825);
DISPLAY 0.872340 (3725 825);
DISPLAY INVISIBLE (3725 825);
FORCEPROP 1 LAST PATH I109
J 0
(3398 950);
DISPLAY 0.872340 (3398 950);
PAINT GREEN (3398 950);
DISPLAY INVISIBLE (3398 950);
FORCEADD TAP..1
R 2
(-25 200);
FORCEPROP 3 LASTPIN (25 200) SIG_NAME M_D_CPU0_SB_CB<5>
J 0
(35 210);
DISPLAY 0.659574 (35 210);
PAINT MONO (35 210);
DISPLAY INVISIBLE (35 210);
FORCEPROP 1 LASTPIN (25 200) BN 5
J 2
(37 208);
DISPLAY 0.680851 (37 208);
PAINT GREEN (37 208);
FORCEPROP 2 LAST CDS_LIB standard
J 0
(-25 200);
DISPLAY INVISIBLE (-25 200);
FORCEPROP 1 LAST BODY_TYPE PLUMBING
J 2
(-25 250);
DISPLAY 0.872340 (-25 250);
PAINT GREEN (-25 250);
DISPLAY INVISIBLE (-25 250);
FORCEPROP 1 LAST HDL_TAP TRUE
J 2
(-350 75);
DISPLAY 0.872340 (-350 75);
DISPLAY INVISIBLE (-350 75);
FORCEPROP 1 LAST PATH I11
J 2
(-23 200);
DISPLAY 0.872340 (-23 200);
PAINT GREEN (-23 200);
DISPLAY INVISIBLE (-23 200);
FORCEADD TAP..1
(3400 1050);
FORCEPROP 3 LASTPIN (3350 1050) SIG_NAME M_D_CPU0_SB_CA<5>
J 0
(3360 1060);
DISPLAY 0.659574 (3360 1060);
PAINT MONO (3360 1060);
DISPLAY INVISIBLE (3360 1060);
FORCEPROP 1 LASTPIN (3350 1050) BN 5
J 0
(3338 1058);
DISPLAY 0.680851 (3338 1058);
PAINT GREEN (3338 1058);
FORCEPROP 2 LAST CDS_LIB standard
J 0
(3400 1050);
DISPLAY INVISIBLE (3400 1050);
FORCEPROP 1 LAST BODY_TYPE PLUMBING
J 0
(3400 1100);
DISPLAY 0.872340 (3400 1100);
PAINT GREEN (3400 1100);
DISPLAY INVISIBLE (3400 1100);
FORCEPROP 1 LAST HDL_TAP TRUE
J 0
(3725 925);
DISPLAY 0.872340 (3725 925);
DISPLAY INVISIBLE (3725 925);
FORCEPROP 1 LAST PATH I110
J 0
(3398 1050);
DISPLAY 0.872340 (3398 1050);
PAINT GREEN (3398 1050);
DISPLAY INVISIBLE (3398 1050);
FORCEADD TAP..1
(3400 1100);
FORCEPROP 3 LASTPIN (3350 1100) SIG_NAME M_D_CPU0_SB_CA<6>
J 0
(3360 1110);
DISPLAY 0.659574 (3360 1110);
PAINT MONO (3360 1110);
DISPLAY INVISIBLE (3360 1110);
FORCEPROP 1 LASTPIN (3350 1100) BN 6
J 0
(3338 1108);
DISPLAY 0.680851 (3338 1108);
PAINT GREEN (3338 1108);
FORCEPROP 2 LAST CDS_LIB standard
J 0
(3400 1100);
DISPLAY INVISIBLE (3400 1100);
FORCEPROP 1 LAST BODY_TYPE PLUMBING
J 0
(3400 1150);
DISPLAY 0.872340 (3400 1150);
PAINT GREEN (3400 1150);
DISPLAY INVISIBLE (3400 1150);
FORCEPROP 1 LAST HDL_TAP TRUE
J 0
(3725 975);
DISPLAY 0.872340 (3725 975);
DISPLAY INVISIBLE (3725 975);
FORCEPROP 1 LAST PATH I111
J 0
(3398 1100);
DISPLAY 0.872340 (3398 1100);
PAINT GREEN (3398 1100);
DISPLAY INVISIBLE (3398 1100);
FORCEADD TAP..1
(3400 1400);
FORCEPROP 3 LASTPIN (3350 1400) SIG_NAME M_D_CPU0_SA_CA<2>
J 0
(3360 1410);
DISPLAY 0.659574 (3360 1410);
PAINT MONO (3360 1410);
DISPLAY INVISIBLE (3360 1410);
FORCEPROP 1 LASTPIN (3350 1400) BN 2
J 0
(3338 1408);
DISPLAY 0.680851 (3338 1408);
PAINT GREEN (3338 1408);
FORCEPROP 2 LAST CDS_LIB standard
J 0
(3400 1400);
DISPLAY INVISIBLE (3400 1400);
FORCEPROP 1 LAST BODY_TYPE PLUMBING
J 0
(3400 1450);
DISPLAY 0.872340 (3400 1450);
PAINT GREEN (3400 1450);
DISPLAY INVISIBLE (3400 1450);
FORCEPROP 1 LAST HDL_TAP TRUE
J 0
(3725 1275);
DISPLAY 0.872340 (3725 1275);
DISPLAY INVISIBLE (3725 1275);
FORCEPROP 1 LAST PATH I112
J 0
(3398 1400);
DISPLAY 0.872340 (3398 1400);
PAINT GREEN (3398 1400);
DISPLAY INVISIBLE (3398 1400);
FORCEADD TAP..1
(3400 1350);
FORCEPROP 3 LASTPIN (3350 1350) SIG_NAME M_D_CPU0_SA_CA<1>
J 0
(3360 1360);
DISPLAY 0.659574 (3360 1360);
PAINT MONO (3360 1360);
DISPLAY INVISIBLE (3360 1360);
FORCEPROP 1 LASTPIN (3350 1350) BN 1
J 0
(3338 1358);
DISPLAY 0.680851 (3338 1358);
PAINT GREEN (3338 1358);
FORCEPROP 2 LAST CDS_LIB standard
J 0
(3400 1350);
DISPLAY INVISIBLE (3400 1350);
FORCEPROP 1 LAST BODY_TYPE PLUMBING
J 0
(3400 1400);
DISPLAY 0.872340 (3400 1400);
PAINT GREEN (3400 1400);
DISPLAY INVISIBLE (3400 1400);
FORCEPROP 1 LAST HDL_TAP TRUE
J 0
(3725 1225);
DISPLAY 0.872340 (3725 1225);
DISPLAY INVISIBLE (3725 1225);
FORCEPROP 1 LAST PATH I113
J 0
(3398 1350);
DISPLAY 0.872340 (3398 1350);
PAINT GREEN (3398 1350);
DISPLAY INVISIBLE (3398 1350);
FORCEADD TAP..1
(3400 1300);
FORCEPROP 3 LASTPIN (3350 1300) SIG_NAME M_D_CPU0_SA_CA<0>
J 0
(3360 1310);
DISPLAY 0.659574 (3360 1310);
PAINT MONO (3360 1310);
DISPLAY INVISIBLE (3360 1310);
FORCEPROP 1 LASTPIN (3350 1300) BN 0
J 0
(3338 1308);
DISPLAY 0.680851 (3338 1308);
PAINT GREEN (3338 1308);
FORCEPROP 2 LAST CDS_LIB standard
J 0
(3400 1300);
DISPLAY INVISIBLE (3400 1300);
FORCEPROP 1 LAST BODY_TYPE PLUMBING
J 0
(3400 1350);
DISPLAY 0.872340 (3400 1350);
PAINT GREEN (3400 1350);
DISPLAY INVISIBLE (3400 1350);
FORCEPROP 1 LAST HDL_TAP TRUE
J 0
(3725 1175);
DISPLAY 0.872340 (3725 1175);
DISPLAY INVISIBLE (3725 1175);
FORCEPROP 1 LAST PATH I114
J 0
(3398 1300);
DISPLAY 0.872340 (3398 1300);
PAINT GREEN (3398 1300);
DISPLAY INVISIBLE (3398 1300);
FORCEADD TAP..1
(3400 1550);
FORCEPROP 3 LASTPIN (3350 1550) SIG_NAME M_D_CPU0_SA_CA<5>
J 0
(3360 1560);
DISPLAY 0.659574 (3360 1560);
PAINT MONO (3360 1560);
DISPLAY INVISIBLE (3360 1560);
FORCEPROP 1 LASTPIN (3350 1550) BN 5
J 0
(3338 1558);
DISPLAY 0.680851 (3338 1558);
PAINT GREEN (3338 1558);
FORCEPROP 2 LAST CDS_LIB standard
J 0
(3400 1550);
DISPLAY INVISIBLE (3400 1550);
FORCEPROP 1 LAST BODY_TYPE PLUMBING
J 0
(3400 1600);
DISPLAY 0.872340 (3400 1600);
PAINT GREEN (3400 1600);
DISPLAY INVISIBLE (3400 1600);
FORCEPROP 1 LAST HDL_TAP TRUE
J 0
(3725 1425);
DISPLAY 0.872340 (3725 1425);
DISPLAY INVISIBLE (3725 1425);
FORCEPROP 1 LAST PATH I115
J 0
(3398 1550);
DISPLAY 0.872340 (3398 1550);
PAINT GREEN (3398 1550);
DISPLAY INVISIBLE (3398 1550);
FORCEADD TAP..1
(3400 1450);
FORCEPROP 3 LASTPIN (3350 1450) SIG_NAME M_D_CPU0_SA_CA<3>
J 0
(3360 1460);
DISPLAY 0.659574 (3360 1460);
PAINT MONO (3360 1460);
DISPLAY INVISIBLE (3360 1460);
FORCEPROP 1 LASTPIN (3350 1450) BN 3
J 0
(3338 1458);
DISPLAY 0.680851 (3338 1458);
PAINT GREEN (3338 1458);
FORCEPROP 2 LAST CDS_LIB standard
J 0
(3400 1450);
DISPLAY INVISIBLE (3400 1450);
FORCEPROP 1 LAST BODY_TYPE PLUMBING
J 0
(3400 1500);
DISPLAY 0.872340 (3400 1500);
PAINT GREEN (3400 1500);
DISPLAY INVISIBLE (3400 1500);
FORCEPROP 1 LAST HDL_TAP TRUE
J 0
(3725 1325);
DISPLAY 0.872340 (3725 1325);
DISPLAY INVISIBLE (3725 1325);
FORCEPROP 1 LAST PATH I116
J 0
(3398 1450);
DISPLAY 0.872340 (3398 1450);
PAINT GREEN (3398 1450);
DISPLAY INVISIBLE (3398 1450);
FORCEADD TAP..1
(3400 1500);
FORCEPROP 3 LASTPIN (3350 1500) SIG_NAME M_D_CPU0_SA_CA<4>
J 0
(3360 1510);
DISPLAY 0.659574 (3360 1510);
PAINT MONO (3360 1510);
DISPLAY INVISIBLE (3360 1510);
FORCEPROP 1 LASTPIN (3350 1500) BN 4
J 0
(3338 1508);
DISPLAY 0.680851 (3338 1508);
PAINT GREEN (3338 1508);
FORCEPROP 2 LAST CDS_LIB standard
J 0
(3400 1500);
DISPLAY INVISIBLE (3400 1500);
FORCEPROP 1 LAST BODY_TYPE PLUMBING
J 0
(3400 1550);
DISPLAY 0.872340 (3400 1550);
PAINT GREEN (3400 1550);
DISPLAY INVISIBLE (3400 1550);
FORCEPROP 1 LAST HDL_TAP TRUE
J 0
(3725 1375);
DISPLAY 0.872340 (3725 1375);
DISPLAY INVISIBLE (3725 1375);
FORCEPROP 1 LAST PATH I117
J 0
(3398 1500);
DISPLAY 0.872340 (3398 1500);
PAINT GREEN (3398 1500);
DISPLAY INVISIBLE (3398 1500);
FORCEADD TAP..1
(3400 1600);
FORCEPROP 3 LASTPIN (3350 1600) SIG_NAME M_D_CPU0_SA_CA<6>
J 0
(3360 1610);
DISPLAY 0.659574 (3360 1610);
PAINT MONO (3360 1610);
DISPLAY INVISIBLE (3360 1610);
FORCEPROP 1 LASTPIN (3350 1600) BN 6
J 0
(3338 1608);
DISPLAY 0.680851 (3338 1608);
PAINT GREEN (3338 1608);
FORCEPROP 2 LAST CDS_LIB standard
J 0
(3400 1600);
DISPLAY INVISIBLE (3400 1600);
FORCEPROP 1 LAST BODY_TYPE PLUMBING
J 0
(3400 1650);
DISPLAY 0.872340 (3400 1650);
PAINT GREEN (3400 1650);
DISPLAY INVISIBLE (3400 1650);
FORCEPROP 1 LAST HDL_TAP TRUE
J 0
(3725 1475);
DISPLAY 0.872340 (3725 1475);
DISPLAY INVISIBLE (3725 1475);
FORCEPROP 1 LAST PATH I118
J 0
(3398 1600);
DISPLAY 0.872340 (3398 1600);
PAINT GREEN (3398 1600);
DISPLAY INVISIBLE (3398 1600);
FORCEADD TAP..1
(3400 1750);
FORCEPROP 3 LASTPIN (3350 1750) SIG_NAME M_D_CPU0_SB_DQS_DN<0>
J 0
(3360 1760);
DISPLAY 0.659574 (3360 1760);
PAINT MONO (3360 1760);
DISPLAY INVISIBLE (3360 1760);
FORCEPROP 1 LASTPIN (3350 1750) BN 0
J 0
(3338 1758);
DISPLAY 0.680851 (3338 1758);
PAINT GREEN (3338 1758);
FORCEPROP 2 LAST CDS_LIB standard
J 0
(3400 1750);
DISPLAY INVISIBLE (3400 1750);
FORCEPROP 1 LAST BODY_TYPE PLUMBING
J 0
(3400 1800);
DISPLAY 0.872340 (3400 1800);
PAINT GREEN (3400 1800);
DISPLAY INVISIBLE (3400 1800);
FORCEPROP 1 LAST HDL_TAP TRUE
J 0
(3725 1625);
DISPLAY 0.872340 (3725 1625);
DISPLAY INVISIBLE (3725 1625);
FORCEPROP 1 LAST PATH I119
J 0
(3398 1750);
DISPLAY 0.872340 (3398 1750);
PAINT GREEN (3398 1750);
DISPLAY INVISIBLE (3398 1750);
FORCEADD TAP..1
R 2
(-25 150);
FORCEPROP 3 LASTPIN (25 150) SIG_NAME M_D_CPU0_SB_CB<4>
J 0
(35 160);
DISPLAY 0.659574 (35 160);
PAINT MONO (35 160);
DISPLAY INVISIBLE (35 160);
FORCEPROP 1 LASTPIN (25 150) BN 4
J 2
(37 158);
DISPLAY 0.680851 (37 158);
PAINT GREEN (37 158);
FORCEPROP 2 LAST CDS_LIB standard
J 0
(-25 150);
DISPLAY INVISIBLE (-25 150);
FORCEPROP 1 LAST BODY_TYPE PLUMBING
J 2
(-25 200);
DISPLAY 0.872340 (-25 200);
PAINT GREEN (-25 200);
DISPLAY INVISIBLE (-25 200);
FORCEPROP 1 LAST HDL_TAP TRUE
J 2
(-350 25);
DISPLAY 0.872340 (-350 25);
DISPLAY INVISIBLE (-350 25);
FORCEPROP 1 LAST PATH I12
J 2
(-23 150);
DISPLAY 0.872340 (-23 150);
PAINT GREEN (-23 150);
DISPLAY INVISIBLE (-23 150);
FORCEADD TAP..1
(3400 1800);
FORCEPROP 3 LASTPIN (3350 1800) SIG_NAME M_D_CPU0_SB_DQS_DN<1>
J 0
(3360 1810);
DISPLAY 0.659574 (3360 1810);
PAINT MONO (3360 1810);
DISPLAY INVISIBLE (3360 1810);
FORCEPROP 1 LASTPIN (3350 1800) BN 1
J 0
(3338 1808);
DISPLAY 0.680851 (3338 1808);
PAINT GREEN (3338 1808);
FORCEPROP 2 LAST CDS_LIB standard
J 0
(3400 1800);
DISPLAY INVISIBLE (3400 1800);
FORCEPROP 1 LAST BODY_TYPE PLUMBING
J 0
(3400 1850);
DISPLAY 0.872340 (3400 1850);
PAINT GREEN (3400 1850);
DISPLAY INVISIBLE (3400 1850);
FORCEPROP 1 LAST HDL_TAP TRUE
J 0
(3725 1675);
DISPLAY 0.872340 (3725 1675);
DISPLAY INVISIBLE (3725 1675);
FORCEPROP 1 LAST PATH I120
J 0
(3398 1800);
DISPLAY 0.872340 (3398 1800);
PAINT GREEN (3398 1800);
DISPLAY INVISIBLE (3398 1800);
FORCEADD TAP..1
(3400 1900);
FORCEPROP 3 LASTPIN (3350 1900) SIG_NAME M_D_CPU0_SB_DQS_DN<3>
J 0
(3360 1910);
DISPLAY 0.659574 (3360 1910);
PAINT MONO (3360 1910);
DISPLAY INVISIBLE (3360 1910);
FORCEPROP 1 LASTPIN (3350 1900) BN 3
J 0
(3338 1908);
DISPLAY 0.680851 (3338 1908);
PAINT GREEN (3338 1908);
FORCEPROP 2 LAST CDS_LIB standard
J 0
(3400 1900);
DISPLAY INVISIBLE (3400 1900);
FORCEPROP 1 LAST BODY_TYPE PLUMBING
J 0
(3400 1950);
DISPLAY 0.872340 (3400 1950);
PAINT GREEN (3400 1950);
DISPLAY INVISIBLE (3400 1950);
FORCEPROP 1 LAST HDL_TAP TRUE
J 0
(3725 1775);
DISPLAY 0.872340 (3725 1775);
DISPLAY INVISIBLE (3725 1775);
FORCEPROP 1 LAST PATH I121
J 0
(3398 1900);
DISPLAY 0.872340 (3398 1900);
PAINT GREEN (3398 1900);
DISPLAY INVISIBLE (3398 1900);
FORCEADD TAP..1
(3400 1850);
FORCEPROP 3 LASTPIN (3350 1850) SIG_NAME M_D_CPU0_SB_DQS_DN<2>
J 0
(3360 1860);
DISPLAY 0.659574 (3360 1860);
PAINT MONO (3360 1860);
DISPLAY INVISIBLE (3360 1860);
FORCEPROP 1 LASTPIN (3350 1850) BN 2
J 0
(3338 1858);
DISPLAY 0.680851 (3338 1858);
PAINT GREEN (3338 1858);
FORCEPROP 2 LAST CDS_LIB standard
J 0
(3400 1850);
DISPLAY INVISIBLE (3400 1850);
FORCEPROP 1 LAST BODY_TYPE PLUMBING
J 0
(3400 1900);
DISPLAY 0.872340 (3400 1900);
PAINT GREEN (3400 1900);
DISPLAY INVISIBLE (3400 1900);
FORCEPROP 1 LAST HDL_TAP TRUE
J 0
(3725 1725);
DISPLAY 0.872340 (3725 1725);
DISPLAY INVISIBLE (3725 1725);
FORCEPROP 1 LAST PATH I122
J 0
(3398 1850);
DISPLAY 0.872340 (3398 1850);
PAINT GREEN (3398 1850);
DISPLAY INVISIBLE (3398 1850);
FORCEADD TAP..1
(3400 1950);
FORCEPROP 3 LASTPIN (3350 1950) SIG_NAME M_D_CPU0_SB_DQS_DN<4>
J 0
(3360 1960);
DISPLAY 0.659574 (3360 1960);
PAINT MONO (3360 1960);
DISPLAY INVISIBLE (3360 1960);
FORCEPROP 1 LASTPIN (3350 1950) BN 4
J 0
(3338 1958);
DISPLAY 0.680851 (3338 1958);
PAINT GREEN (3338 1958);
FORCEPROP 2 LAST CDS_LIB standard
J 0
(3400 1950);
DISPLAY INVISIBLE (3400 1950);
FORCEPROP 1 LAST BODY_TYPE PLUMBING
J 0
(3400 2000);
DISPLAY 0.872340 (3400 2000);
PAINT GREEN (3400 2000);
DISPLAY INVISIBLE (3400 2000);
FORCEPROP 1 LAST HDL_TAP TRUE
J 0
(3725 1825);
DISPLAY 0.872340 (3725 1825);
DISPLAY INVISIBLE (3725 1825);
FORCEPROP 1 LAST PATH I123
J 0
(3398 1950);
DISPLAY 0.872340 (3398 1950);
PAINT GREEN (3398 1950);
DISPLAY INVISIBLE (3398 1950);
FORCEADD TAP..1
(3400 2050);
FORCEPROP 3 LASTPIN (3350 2050) SIG_NAME M_D_CPU0_SB_DQS_DN<6>
J 0
(3360 2060);
DISPLAY 0.659574 (3360 2060);
PAINT MONO (3360 2060);
DISPLAY INVISIBLE (3360 2060);
FORCEPROP 1 LASTPIN (3350 2050) BN 6
J 0
(3338 2058);
DISPLAY 0.680851 (3338 2058);
PAINT GREEN (3338 2058);
FORCEPROP 2 LAST CDS_LIB standard
J 0
(3400 2050);
DISPLAY INVISIBLE (3400 2050);
FORCEPROP 1 LAST BODY_TYPE PLUMBING
J 0
(3400 2100);
DISPLAY 0.872340 (3400 2100);
PAINT GREEN (3400 2100);
DISPLAY INVISIBLE (3400 2100);
FORCEPROP 1 LAST HDL_TAP TRUE
J 0
(3725 1925);
DISPLAY 0.872340 (3725 1925);
DISPLAY INVISIBLE (3725 1925);
FORCEPROP 1 LAST PATH I124
J 0
(3398 2050);
DISPLAY 0.872340 (3398 2050);
PAINT GREEN (3398 2050);
DISPLAY INVISIBLE (3398 2050);
FORCEADD TAP..1
(3400 2000);
FORCEPROP 3 LASTPIN (3350 2000) SIG_NAME M_D_CPU0_SB_DQS_DN<5>
J 0
(3360 2010);
DISPLAY 0.659574 (3360 2010);
PAINT MONO (3360 2010);
DISPLAY INVISIBLE (3360 2010);
FORCEPROP 1 LASTPIN (3350 2000) BN 5
J 0
(3338 2008);
DISPLAY 0.680851 (3338 2008);
PAINT GREEN (3338 2008);
FORCEPROP 2 LAST CDS_LIB standard
J 0
(3400 2000);
DISPLAY INVISIBLE (3400 2000);
FORCEPROP 1 LAST BODY_TYPE PLUMBING
J 0
(3400 2050);
DISPLAY 0.872340 (3400 2050);
PAINT GREEN (3400 2050);
DISPLAY INVISIBLE (3400 2050);
FORCEPROP 1 LAST HDL_TAP TRUE
J 0
(3725 1875);
DISPLAY 0.872340 (3725 1875);
DISPLAY INVISIBLE (3725 1875);
FORCEPROP 1 LAST PATH I125
J 0
(3398 2000);
DISPLAY 0.872340 (3398 2000);
PAINT GREEN (3398 2000);
DISPLAY INVISIBLE (3398 2000);
FORCEADD TAP..1
(3400 2150);
FORCEPROP 3 LASTPIN (3350 2150) SIG_NAME M_D_CPU0_SB_DQS_DN<8>
J 0
(3360 2160);
DISPLAY 0.659574 (3360 2160);
PAINT MONO (3360 2160);
DISPLAY INVISIBLE (3360 2160);
FORCEPROP 1 LASTPIN (3350 2150) BN 8
J 0
(3338 2158);
DISPLAY 0.680851 (3338 2158);
PAINT GREEN (3338 2158);
FORCEPROP 2 LAST CDS_LIB standard
J 0
(3400 2150);
DISPLAY INVISIBLE (3400 2150);
FORCEPROP 1 LAST BODY_TYPE PLUMBING
J 0
(3400 2200);
DISPLAY 0.872340 (3400 2200);
PAINT GREEN (3400 2200);
DISPLAY INVISIBLE (3400 2200);
FORCEPROP 1 LAST HDL_TAP TRUE
J 0
(3725 2025);
DISPLAY 0.872340 (3725 2025);
DISPLAY INVISIBLE (3725 2025);
FORCEPROP 1 LAST PATH I126
J 0
(3398 2150);
DISPLAY 0.872340 (3398 2150);
PAINT GREEN (3398 2150);
DISPLAY INVISIBLE (3398 2150);
FORCEADD TAP..1
(3400 2100);
FORCEPROP 3 LASTPIN (3350 2100) SIG_NAME M_D_CPU0_SB_DQS_DN<7>
J 0
(3360 2110);
DISPLAY 0.659574 (3360 2110);
PAINT MONO (3360 2110);
DISPLAY INVISIBLE (3360 2110);
FORCEPROP 1 LASTPIN (3350 2100) BN 7
J 0
(3338 2108);
DISPLAY 0.680851 (3338 2108);
PAINT GREEN (3338 2108);
FORCEPROP 2 LAST CDS_LIB standard
J 0
(3400 2100);
DISPLAY INVISIBLE (3400 2100);
FORCEPROP 1 LAST BODY_TYPE PLUMBING
J 0
(3400 2150);
DISPLAY 0.872340 (3400 2150);
PAINT GREEN (3400 2150);
DISPLAY INVISIBLE (3400 2150);
FORCEPROP 1 LAST HDL_TAP TRUE
J 0
(3725 1975);
DISPLAY 0.872340 (3725 1975);
DISPLAY INVISIBLE (3725 1975);
FORCEPROP 1 LAST PATH I127
J 0
(3398 2100);
DISPLAY 0.872340 (3398 2100);
PAINT GREEN (3398 2100);
DISPLAY INVISIBLE (3398 2100);
FORCEADD TAP..1
(3400 2200);
FORCEPROP 3 LASTPIN (3350 2200) SIG_NAME M_D_CPU0_SB_DQS_DN<9>
J 0
(3360 2210);
DISPLAY 0.659574 (3360 2210);
PAINT MONO (3360 2210);
DISPLAY INVISIBLE (3360 2210);
FORCEPROP 1 LASTPIN (3350 2200) BN 9
J 0
(3338 2208);
DISPLAY 0.680851 (3338 2208);
PAINT GREEN (3338 2208);
FORCEPROP 2 LAST CDS_LIB standard
J 0
(3400 2200);
DISPLAY INVISIBLE (3400 2200);
FORCEPROP 1 LAST BODY_TYPE PLUMBING
J 0
(3400 2250);
DISPLAY 0.872340 (3400 2250);
PAINT GREEN (3400 2250);
DISPLAY INVISIBLE (3400 2250);
FORCEPROP 1 LAST HDL_TAP TRUE
J 0
(3725 2075);
DISPLAY 0.872340 (3725 2075);
DISPLAY INVISIBLE (3725 2075);
FORCEPROP 1 LAST PATH I128
J 0
(3398 2200);
DISPLAY 0.872340 (3398 2200);
PAINT GREEN (3398 2200);
DISPLAY INVISIBLE (3398 2200);
FORCEADD TAP..1
(3400 2300);
FORCEPROP 3 LASTPIN (3350 2300) SIG_NAME M_D_CPU0_SB_DQS_DP<0>
J 0
(3360 2310);
DISPLAY 0.659574 (3360 2310);
PAINT MONO (3360 2310);
DISPLAY INVISIBLE (3360 2310);
FORCEPROP 1 LASTPIN (3350 2300) BN 0
J 0
(3338 2308);
DISPLAY 0.680851 (3338 2308);
PAINT GREEN (3338 2308);
FORCEPROP 2 LAST CDS_LIB standard
J 0
(3400 2300);
DISPLAY INVISIBLE (3400 2300);
FORCEPROP 1 LAST BODY_TYPE PLUMBING
J 0
(3400 2350);
DISPLAY 0.872340 (3400 2350);
PAINT GREEN (3400 2350);
DISPLAY INVISIBLE (3400 2350);
FORCEPROP 1 LAST HDL_TAP TRUE
J 0
(3725 2175);
DISPLAY 0.872340 (3725 2175);
DISPLAY INVISIBLE (3725 2175);
FORCEPROP 1 LAST PATH I129
J 0
(3398 2300);
DISPLAY 0.872340 (3398 2300);
PAINT GREEN (3398 2300);
DISPLAY INVISIBLE (3398 2300);
FORCEADD TAP..1
R 2
(-25 250);
FORCEPROP 3 LASTPIN (25 250) SIG_NAME M_D_CPU0_SB_CB<6>
J 0
(35 260);
DISPLAY 0.659574 (35 260);
PAINT MONO (35 260);
DISPLAY INVISIBLE (35 260);
FORCEPROP 1 LASTPIN (25 250) BN 6
J 2
(37 258);
DISPLAY 0.680851 (37 258);
PAINT GREEN (37 258);
FORCEPROP 2 LAST CDS_LIB standard
J 0
(-25 250);
DISPLAY INVISIBLE (-25 250);
FORCEPROP 1 LAST BODY_TYPE PLUMBING
J 2
(-25 300);
DISPLAY 0.872340 (-25 300);
PAINT GREEN (-25 300);
DISPLAY INVISIBLE (-25 300);
FORCEPROP 1 LAST HDL_TAP TRUE
J 2
(-350 125);
DISPLAY 0.872340 (-350 125);
DISPLAY INVISIBLE (-350 125);
FORCEPROP 1 LAST PATH I13
J 2
(-23 250);
DISPLAY 0.872340 (-23 250);
PAINT GREEN (-23 250);
DISPLAY INVISIBLE (-23 250);
FORCEADD TAP..1
(3400 2400);
FORCEPROP 3 LASTPIN (3350 2400) SIG_NAME M_D_CPU0_SB_DQS_DP<2>
J 0
(3360 2410);
DISPLAY 0.659574 (3360 2410);
PAINT MONO (3360 2410);
DISPLAY INVISIBLE (3360 2410);
FORCEPROP 1 LASTPIN (3350 2400) BN 2
J 0
(3338 2408);
DISPLAY 0.680851 (3338 2408);
PAINT GREEN (3338 2408);
FORCEPROP 2 LAST CDS_LIB standard
J 0
(3400 2400);
DISPLAY INVISIBLE (3400 2400);
FORCEPROP 1 LAST BODY_TYPE PLUMBING
J 0
(3400 2450);
DISPLAY 0.872340 (3400 2450);
PAINT GREEN (3400 2450);
DISPLAY INVISIBLE (3400 2450);
FORCEPROP 1 LAST HDL_TAP TRUE
J 0
(3725 2275);
DISPLAY 0.872340 (3725 2275);
DISPLAY INVISIBLE (3725 2275);
FORCEPROP 1 LAST PATH I130
J 0
(3398 2400);
DISPLAY 0.872340 (3398 2400);
PAINT GREEN (3398 2400);
DISPLAY INVISIBLE (3398 2400);
FORCEADD TAP..1
(3400 2350);
FORCEPROP 3 LASTPIN (3350 2350) SIG_NAME M_D_CPU0_SB_DQS_DP<1>
J 0
(3360 2360);
DISPLAY 0.659574 (3360 2360);
PAINT MONO (3360 2360);
DISPLAY INVISIBLE (3360 2360);
FORCEPROP 1 LASTPIN (3350 2350) BN 1
J 0
(3338 2358);
DISPLAY 0.680851 (3338 2358);
PAINT GREEN (3338 2358);
FORCEPROP 2 LAST CDS_LIB standard
J 0
(3400 2350);
DISPLAY INVISIBLE (3400 2350);
FORCEPROP 1 LAST BODY_TYPE PLUMBING
J 0
(3400 2400);
DISPLAY 0.872340 (3400 2400);
PAINT GREEN (3400 2400);
DISPLAY INVISIBLE (3400 2400);
FORCEPROP 1 LAST HDL_TAP TRUE
J 0
(3725 2225);
DISPLAY 0.872340 (3725 2225);
DISPLAY INVISIBLE (3725 2225);
FORCEPROP 1 LAST PATH I131
J 0
(3398 2350);
DISPLAY 0.872340 (3398 2350);
PAINT GREEN (3398 2350);
DISPLAY INVISIBLE (3398 2350);
FORCEADD TAP..1
(3400 2450);
FORCEPROP 3 LASTPIN (3350 2450) SIG_NAME M_D_CPU0_SB_DQS_DP<3>
J 0
(3360 2460);
DISPLAY 0.659574 (3360 2460);
PAINT MONO (3360 2460);
DISPLAY INVISIBLE (3360 2460);
FORCEPROP 1 LASTPIN (3350 2450) BN 3
J 0
(3338 2458);
DISPLAY 0.680851 (3338 2458);
PAINT GREEN (3338 2458);
FORCEPROP 2 LAST CDS_LIB standard
J 0
(3400 2450);
DISPLAY INVISIBLE (3400 2450);
FORCEPROP 1 LAST BODY_TYPE PLUMBING
J 0
(3400 2500);
DISPLAY 0.872340 (3400 2500);
PAINT GREEN (3400 2500);
DISPLAY INVISIBLE (3400 2500);
FORCEPROP 1 LAST HDL_TAP TRUE
J 0
(3725 2325);
DISPLAY 0.872340 (3725 2325);
DISPLAY INVISIBLE (3725 2325);
FORCEPROP 1 LAST PATH I132
J 0
(3398 2450);
DISPLAY 0.872340 (3398 2450);
PAINT GREEN (3398 2450);
DISPLAY INVISIBLE (3398 2450);
FORCEADD TAP..1
(3400 2550);
FORCEPROP 3 LASTPIN (3350 2550) SIG_NAME M_D_CPU0_SB_DQS_DP<5>
J 0
(3360 2560);
DISPLAY 0.659574 (3360 2560);
PAINT MONO (3360 2560);
DISPLAY INVISIBLE (3360 2560);
FORCEPROP 1 LASTPIN (3350 2550) BN 5
J 0
(3338 2558);
DISPLAY 0.680851 (3338 2558);
PAINT GREEN (3338 2558);
FORCEPROP 2 LAST CDS_LIB standard
J 0
(3400 2550);
DISPLAY INVISIBLE (3400 2550);
FORCEPROP 1 LAST BODY_TYPE PLUMBING
J 0
(3400 2600);
DISPLAY 0.872340 (3400 2600);
PAINT GREEN (3400 2600);
DISPLAY INVISIBLE (3400 2600);
FORCEPROP 1 LAST HDL_TAP TRUE
J 0
(3725 2425);
DISPLAY 0.872340 (3725 2425);
DISPLAY INVISIBLE (3725 2425);
FORCEPROP 1 LAST PATH I133
J 0
(3398 2550);
DISPLAY 0.872340 (3398 2550);
PAINT GREEN (3398 2550);
DISPLAY INVISIBLE (3398 2550);
FORCEADD TAP..1
(3400 2500);
FORCEPROP 3 LASTPIN (3350 2500) SIG_NAME M_D_CPU0_SB_DQS_DP<4>
J 0
(3360 2510);
DISPLAY 0.659574 (3360 2510);
PAINT MONO (3360 2510);
DISPLAY INVISIBLE (3360 2510);
FORCEPROP 1 LASTPIN (3350 2500) BN 4
J 0
(3338 2508);
DISPLAY 0.680851 (3338 2508);
PAINT GREEN (3338 2508);
FORCEPROP 2 LAST CDS_LIB standard
J 0
(3400 2500);
DISPLAY INVISIBLE (3400 2500);
FORCEPROP 1 LAST BODY_TYPE PLUMBING
J 0
(3400 2550);
DISPLAY 0.872340 (3400 2550);
PAINT GREEN (3400 2550);
DISPLAY INVISIBLE (3400 2550);
FORCEPROP 1 LAST HDL_TAP TRUE
J 0
(3725 2375);
DISPLAY 0.872340 (3725 2375);
DISPLAY INVISIBLE (3725 2375);
FORCEPROP 1 LAST PATH I134
J 0
(3398 2500);
DISPLAY 0.872340 (3398 2500);
PAINT GREEN (3398 2500);
DISPLAY INVISIBLE (3398 2500);
FORCEADD TAP..1
(3400 2650);
FORCEPROP 3 LASTPIN (3350 2650) SIG_NAME M_D_CPU0_SB_DQS_DP<7>
J 0
(3360 2660);
DISPLAY 0.659574 (3360 2660);
PAINT MONO (3360 2660);
DISPLAY INVISIBLE (3360 2660);
FORCEPROP 1 LASTPIN (3350 2650) BN 7
J 0
(3338 2658);
DISPLAY 0.680851 (3338 2658);
PAINT GREEN (3338 2658);
FORCEPROP 2 LAST CDS_LIB standard
J 0
(3400 2650);
DISPLAY INVISIBLE (3400 2650);
FORCEPROP 1 LAST BODY_TYPE PLUMBING
J 0
(3400 2700);
DISPLAY 0.872340 (3400 2700);
PAINT GREEN (3400 2700);
DISPLAY INVISIBLE (3400 2700);
FORCEPROP 1 LAST HDL_TAP TRUE
J 0
(3725 2525);
DISPLAY 0.872340 (3725 2525);
DISPLAY INVISIBLE (3725 2525);
FORCEPROP 1 LAST PATH I135
J 0
(3398 2650);
DISPLAY 0.872340 (3398 2650);
PAINT GREEN (3398 2650);
DISPLAY INVISIBLE (3398 2650);
FORCEADD TAP..1
(3400 2700);
FORCEPROP 3 LASTPIN (3350 2700) SIG_NAME M_D_CPU0_SB_DQS_DP<8>
J 0
(3360 2710);
DISPLAY 0.659574 (3360 2710);
PAINT MONO (3360 2710);
DISPLAY INVISIBLE (3360 2710);
FORCEPROP 1 LASTPIN (3350 2700) BN 8
J 0
(3338 2708);
DISPLAY 0.680851 (3338 2708);
PAINT GREEN (3338 2708);
FORCEPROP 2 LAST CDS_LIB standard
J 0
(3400 2700);
DISPLAY INVISIBLE (3400 2700);
FORCEPROP 1 LAST BODY_TYPE PLUMBING
J 0
(3400 2750);
DISPLAY 0.872340 (3400 2750);
PAINT GREEN (3400 2750);
DISPLAY INVISIBLE (3400 2750);
FORCEPROP 1 LAST HDL_TAP TRUE
J 0
(3725 2575);
DISPLAY 0.872340 (3725 2575);
DISPLAY INVISIBLE (3725 2575);
FORCEPROP 1 LAST PATH I136
J 0
(3398 2700);
DISPLAY 0.872340 (3398 2700);
PAINT GREEN (3398 2700);
DISPLAY INVISIBLE (3398 2700);
FORCEADD TAP..1
(3400 2600);
FORCEPROP 3 LASTPIN (3350 2600) SIG_NAME M_D_CPU0_SB_DQS_DP<6>
J 0
(3360 2610);
DISPLAY 0.659574 (3360 2610);
PAINT MONO (3360 2610);
DISPLAY INVISIBLE (3360 2610);
FORCEPROP 1 LASTPIN (3350 2600) BN 6
J 0
(3338 2608);
DISPLAY 0.680851 (3338 2608);
PAINT GREEN (3338 2608);
FORCEPROP 2 LAST CDS_LIB standard
J 0
(3400 2600);
DISPLAY INVISIBLE (3400 2600);
FORCEPROP 1 LAST BODY_TYPE PLUMBING
J 0
(3400 2650);
DISPLAY 0.872340 (3400 2650);
PAINT GREEN (3400 2650);
DISPLAY INVISIBLE (3400 2650);
FORCEPROP 1 LAST HDL_TAP TRUE
J 0
(3725 2475);
DISPLAY 0.872340 (3725 2475);
DISPLAY INVISIBLE (3725 2475);
FORCEPROP 1 LAST PATH I137
J 0
(3398 2600);
DISPLAY 0.872340 (3398 2600);
PAINT GREEN (3398 2600);
DISPLAY INVISIBLE (3398 2600);
FORCEADD TAP..1
(3400 2750);
FORCEPROP 3 LASTPIN (3350 2750) SIG_NAME M_D_CPU0_SB_DQS_DP<9>
J 0
(3360 2760);
DISPLAY 0.659574 (3360 2760);
PAINT MONO (3360 2760);
DISPLAY INVISIBLE (3360 2760);
FORCEPROP 1 LASTPIN (3350 2750) BN 9
J 0
(3338 2758);
DISPLAY 0.680851 (3338 2758);
PAINT GREEN (3338 2758);
FORCEPROP 2 LAST CDS_LIB standard
J 0
(3400 2750);
DISPLAY INVISIBLE (3400 2750);
FORCEPROP 1 LAST BODY_TYPE PLUMBING
J 0
(3400 2800);
DISPLAY 0.872340 (3400 2800);
PAINT GREEN (3400 2800);
DISPLAY INVISIBLE (3400 2800);
FORCEPROP 1 LAST HDL_TAP TRUE
J 0
(3725 2625);
DISPLAY 0.872340 (3725 2625);
DISPLAY INVISIBLE (3725 2625);
FORCEPROP 1 LAST PATH I138
J 0
(3398 2750);
DISPLAY 0.872340 (3398 2750);
PAINT GREEN (3398 2750);
DISPLAY INVISIBLE (3398 2750);
FORCEADD TAP..1
(3400 2950);
FORCEPROP 3 LASTPIN (3350 2950) SIG_NAME M_D_CPU0_SA_DQS_DN<1>
J 0
(3360 2960);
DISPLAY 0.659574 (3360 2960);
PAINT MONO (3360 2960);
DISPLAY INVISIBLE (3360 2960);
FORCEPROP 1 LASTPIN (3350 2950) BN 1
J 0
(3338 2958);
DISPLAY 0.680851 (3338 2958);
PAINT GREEN (3338 2958);
FORCEPROP 2 LAST CDS_LIB standard
J 0
(3400 2950);
DISPLAY INVISIBLE (3400 2950);
FORCEPROP 1 LAST BODY_TYPE PLUMBING
J 0
(3400 3000);
DISPLAY 0.872340 (3400 3000);
PAINT GREEN (3400 3000);
DISPLAY INVISIBLE (3400 3000);
FORCEPROP 1 LAST HDL_TAP TRUE
J 0
(3725 2825);
DISPLAY 0.872340 (3725 2825);
DISPLAY INVISIBLE (3725 2825);
FORCEPROP 1 LAST PATH I139
J 0
(3398 2950);
DISPLAY 0.872340 (3398 2950);
PAINT GREEN (3398 2950);
DISPLAY INVISIBLE (3398 2950);
FORCEADD OFFPAGE..3
R 2
(-1050 325);
FORCEPROP 2 LAST $XR1 89 
J 0
(-1419 325);
DISPLAY 0.638298 (-1419 325);
PAINT MONO (-1419 325);
FORCEPROP 2 LAST $XR0 88 
J 0
(-1329 325);
DISPLAY 0.638298 (-1329 325);
PAINT MONO (-1329 325);
FORCEPROP 2 LAST CDS_LIB standard
J 0
(-1050 325);
DISPLAY INVISIBLE (-1050 325);
FORCEPROP 1 LAST OFFPAGE TRUE
J 2
(-1375 200);
DISPLAY 0.872340 (-1375 200);
DISPLAY INVISIBLE (-1375 200);
FORCEPROP 1 LAST COMMENT_BODY TRUE
J 2
(-1000 225);
DISPLAY 0.872340 (-1000 225);
PAINT GREEN (-1000 225);
DISPLAY INVISIBLE (-1000 225);
FORCEPROP 2 LAST PATH I14
J 0
(-1000 400);
DISPLAY 1.021277 (-1000 400);
DISPLAY INVISIBLE (-1000 400);
FORCEADD TAP..1
(3400 2900);
FORCEPROP 3 LASTPIN (3350 2900) SIG_NAME M_D_CPU0_SA_DQS_DN<0>
J 0
(3360 2910);
DISPLAY 0.659574 (3360 2910);
PAINT MONO (3360 2910);
DISPLAY INVISIBLE (3360 2910);
FORCEPROP 1 LASTPIN (3350 2900) BN 0
J 0
(3338 2908);
DISPLAY 0.680851 (3338 2908);
PAINT GREEN (3338 2908);
FORCEPROP 2 LAST CDS_LIB standard
J 0
(3400 2900);
DISPLAY INVISIBLE (3400 2900);
FORCEPROP 1 LAST BODY_TYPE PLUMBING
J 0
(3400 2950);
DISPLAY 0.872340 (3400 2950);
PAINT GREEN (3400 2950);
DISPLAY INVISIBLE (3400 2950);
FORCEPROP 1 LAST HDL_TAP TRUE
J 0
(3725 2775);
DISPLAY 0.872340 (3725 2775);
DISPLAY INVISIBLE (3725 2775);
FORCEPROP 1 LAST PATH I140
J 0
(3398 2900);
DISPLAY 0.872340 (3398 2900);
PAINT GREEN (3398 2900);
DISPLAY INVISIBLE (3398 2900);
FORCEADD TAP..1
(3400 3050);
FORCEPROP 3 LASTPIN (3350 3050) SIG_NAME M_D_CPU0_SA_DQS_DN<3>
J 0
(3360 3060);
DISPLAY 0.659574 (3360 3060);
PAINT MONO (3360 3060);
DISPLAY INVISIBLE (3360 3060);
FORCEPROP 1 LASTPIN (3350 3050) BN 3
J 0
(3338 3058);
DISPLAY 0.680851 (3338 3058);
PAINT GREEN (3338 3058);
FORCEPROP 2 LAST CDS_LIB standard
J 0
(3400 3050);
DISPLAY INVISIBLE (3400 3050);
FORCEPROP 1 LAST BODY_TYPE PLUMBING
J 0
(3400 3100);
DISPLAY 0.872340 (3400 3100);
PAINT GREEN (3400 3100);
DISPLAY INVISIBLE (3400 3100);
FORCEPROP 1 LAST HDL_TAP TRUE
J 0
(3725 2925);
DISPLAY 0.872340 (3725 2925);
DISPLAY INVISIBLE (3725 2925);
FORCEPROP 1 LAST PATH I141
J 0
(3398 3050);
DISPLAY 0.872340 (3398 3050);
PAINT GREEN (3398 3050);
DISPLAY INVISIBLE (3398 3050);
FORCEADD TAP..1
(3400 3000);
FORCEPROP 3 LASTPIN (3350 3000) SIG_NAME M_D_CPU0_SA_DQS_DN<2>
J 0
(3360 3010);
DISPLAY 0.659574 (3360 3010);
PAINT MONO (3360 3010);
DISPLAY INVISIBLE (3360 3010);
FORCEPROP 1 LASTPIN (3350 3000) BN 2
J 0
(3338 3008);
DISPLAY 0.680851 (3338 3008);
PAINT GREEN (3338 3008);
FORCEPROP 2 LAST CDS_LIB standard
J 0
(3400 3000);
DISPLAY INVISIBLE (3400 3000);
FORCEPROP 1 LAST BODY_TYPE PLUMBING
J 0
(3400 3050);
DISPLAY 0.872340 (3400 3050);
PAINT GREEN (3400 3050);
DISPLAY INVISIBLE (3400 3050);
FORCEPROP 1 LAST HDL_TAP TRUE
J 0
(3725 2875);
DISPLAY 0.872340 (3725 2875);
DISPLAY INVISIBLE (3725 2875);
FORCEPROP 1 LAST PATH I142
J 0
(3398 3000);
DISPLAY 0.872340 (3398 3000);
PAINT GREEN (3398 3000);
DISPLAY INVISIBLE (3398 3000);
FORCEADD TAP..1
(3400 3200);
FORCEPROP 3 LASTPIN (3350 3200) SIG_NAME M_D_CPU0_SA_DQS_DN<6>
J 0
(3360 3210);
DISPLAY 0.659574 (3360 3210);
PAINT MONO (3360 3210);
DISPLAY INVISIBLE (3360 3210);
FORCEPROP 1 LASTPIN (3350 3200) BN 6
J 0
(3338 3208);
DISPLAY 0.680851 (3338 3208);
PAINT GREEN (3338 3208);
FORCEPROP 2 LAST CDS_LIB standard
J 0
(3400 3200);
DISPLAY INVISIBLE (3400 3200);
FORCEPROP 1 LAST BODY_TYPE PLUMBING
J 0
(3400 3250);
DISPLAY 0.872340 (3400 3250);
PAINT GREEN (3400 3250);
DISPLAY INVISIBLE (3400 3250);
FORCEPROP 1 LAST HDL_TAP TRUE
J 0
(3725 3075);
DISPLAY 0.872340 (3725 3075);
DISPLAY INVISIBLE (3725 3075);
FORCEPROP 1 LAST PATH I143
J 0
(3398 3200);
DISPLAY 0.872340 (3398 3200);
PAINT GREEN (3398 3200);
DISPLAY INVISIBLE (3398 3200);
FORCEADD TAP..1
(3400 3150);
FORCEPROP 3 LASTPIN (3350 3150) SIG_NAME M_D_CPU0_SA_DQS_DN<5>
J 0
(3360 3160);
DISPLAY 0.659574 (3360 3160);
PAINT MONO (3360 3160);
DISPLAY INVISIBLE (3360 3160);
FORCEPROP 1 LASTPIN (3350 3150) BN 5
J 0
(3338 3158);
DISPLAY 0.680851 (3338 3158);
PAINT GREEN (3338 3158);
FORCEPROP 2 LAST CDS_LIB standard
J 0
(3400 3150);
DISPLAY INVISIBLE (3400 3150);
FORCEPROP 1 LAST BODY_TYPE PLUMBING
J 0
(3400 3200);
DISPLAY 0.872340 (3400 3200);
PAINT GREEN (3400 3200);
DISPLAY INVISIBLE (3400 3200);
FORCEPROP 1 LAST HDL_TAP TRUE
J 0
(3725 3025);
DISPLAY 0.872340 (3725 3025);
DISPLAY INVISIBLE (3725 3025);
FORCEPROP 1 LAST PATH I144
J 0
(3398 3150);
DISPLAY 0.872340 (3398 3150);
PAINT GREEN (3398 3150);
DISPLAY INVISIBLE (3398 3150);
FORCEADD TAP..1
(3400 3100);
FORCEPROP 3 LASTPIN (3350 3100) SIG_NAME M_D_CPU0_SA_DQS_DN<4>
J 0
(3360 3110);
DISPLAY 0.659574 (3360 3110);
PAINT MONO (3360 3110);
DISPLAY INVISIBLE (3360 3110);
FORCEPROP 1 LASTPIN (3350 3100) BN 4
J 0
(3338 3108);
DISPLAY 0.680851 (3338 3108);
PAINT GREEN (3338 3108);
FORCEPROP 2 LAST CDS_LIB standard
J 0
(3400 3100);
DISPLAY INVISIBLE (3400 3100);
FORCEPROP 1 LAST BODY_TYPE PLUMBING
J 0
(3400 3150);
DISPLAY 0.872340 (3400 3150);
PAINT GREEN (3400 3150);
DISPLAY INVISIBLE (3400 3150);
FORCEPROP 1 LAST HDL_TAP TRUE
J 0
(3725 2975);
DISPLAY 0.872340 (3725 2975);
DISPLAY INVISIBLE (3725 2975);
FORCEPROP 1 LAST PATH I145
J 0
(3398 3100);
DISPLAY 0.872340 (3398 3100);
PAINT GREEN (3398 3100);
DISPLAY INVISIBLE (3398 3100);
FORCEADD TAP..1
(3400 3250);
FORCEPROP 3 LASTPIN (3350 3250) SIG_NAME M_D_CPU0_SA_DQS_DN<7>
J 0
(3360 3260);
DISPLAY 0.659574 (3360 3260);
PAINT MONO (3360 3260);
DISPLAY INVISIBLE (3360 3260);
FORCEPROP 1 LASTPIN (3350 3250) BN 7
J 0
(3338 3258);
DISPLAY 0.680851 (3338 3258);
PAINT GREEN (3338 3258);
FORCEPROP 2 LAST CDS_LIB standard
J 0
(3400 3250);
DISPLAY INVISIBLE (3400 3250);
FORCEPROP 1 LAST BODY_TYPE PLUMBING
J 0
(3400 3300);
DISPLAY 0.872340 (3400 3300);
PAINT GREEN (3400 3300);
DISPLAY INVISIBLE (3400 3300);
FORCEPROP 1 LAST HDL_TAP TRUE
J 0
(3725 3125);
DISPLAY 0.872340 (3725 3125);
DISPLAY INVISIBLE (3725 3125);
FORCEPROP 1 LAST PATH I146
J 0
(3398 3250);
DISPLAY 0.872340 (3398 3250);
PAINT GREEN (3398 3250);
DISPLAY INVISIBLE (3398 3250);
FORCEADD TAP..1
(3400 3300);
FORCEPROP 3 LASTPIN (3350 3300) SIG_NAME M_D_CPU0_SA_DQS_DN<8>
J 0
(3360 3310);
DISPLAY 0.659574 (3360 3310);
PAINT MONO (3360 3310);
DISPLAY INVISIBLE (3360 3310);
FORCEPROP 1 LASTPIN (3350 3300) BN 8
J 0
(3338 3308);
DISPLAY 0.680851 (3338 3308);
PAINT GREEN (3338 3308);
FORCEPROP 2 LAST CDS_LIB standard
J 0
(3400 3300);
DISPLAY INVISIBLE (3400 3300);
FORCEPROP 1 LAST BODY_TYPE PLUMBING
J 0
(3400 3350);
DISPLAY 0.872340 (3400 3350);
PAINT GREEN (3400 3350);
DISPLAY INVISIBLE (3400 3350);
FORCEPROP 1 LAST HDL_TAP TRUE
J 0
(3725 3175);
DISPLAY 0.872340 (3725 3175);
DISPLAY INVISIBLE (3725 3175);
FORCEPROP 1 LAST PATH I147
J 0
(3398 3300);
DISPLAY 0.872340 (3398 3300);
PAINT GREEN (3398 3300);
DISPLAY INVISIBLE (3398 3300);
FORCEADD TAP..1
(3400 3350);
FORCEPROP 3 LASTPIN (3350 3350) SIG_NAME M_D_CPU0_SA_DQS_DN<9>
J 0
(3360 3360);
DISPLAY 0.659574 (3360 3360);
PAINT MONO (3360 3360);
DISPLAY INVISIBLE (3360 3360);
FORCEPROP 1 LASTPIN (3350 3350) BN 9
J 0
(3338 3358);
DISPLAY 0.680851 (3338 3358);
PAINT GREEN (3338 3358);
FORCEPROP 2 LAST CDS_LIB standard
J 0
(3400 3350);
DISPLAY INVISIBLE (3400 3350);
FORCEPROP 1 LAST BODY_TYPE PLUMBING
J 0
(3400 3400);
DISPLAY 0.872340 (3400 3400);
PAINT GREEN (3400 3400);
DISPLAY INVISIBLE (3400 3400);
FORCEPROP 1 LAST HDL_TAP TRUE
J 0
(3725 3225);
DISPLAY 0.872340 (3725 3225);
DISPLAY INVISIBLE (3725 3225);
FORCEPROP 1 LAST PATH I148
J 0
(3398 3350);
DISPLAY 0.872340 (3398 3350);
PAINT GREEN (3398 3350);
DISPLAY INVISIBLE (3398 3350);
FORCEADD TAP..1
(3400 3450);
FORCEPROP 3 LASTPIN (3350 3450) SIG_NAME M_D_CPU0_SA_DQS_DP<0>
J 0
(3360 3460);
DISPLAY 0.659574 (3360 3460);
PAINT MONO (3360 3460);
DISPLAY INVISIBLE (3360 3460);
FORCEPROP 1 LASTPIN (3350 3450) BN 0
J 0
(3338 3458);
DISPLAY 0.680851 (3338 3458);
PAINT GREEN (3338 3458);
FORCEPROP 2 LAST CDS_LIB standard
J 0
(3400 3450);
DISPLAY INVISIBLE (3400 3450);
FORCEPROP 1 LAST BODY_TYPE PLUMBING
J 0
(3400 3500);
DISPLAY 0.872340 (3400 3500);
PAINT GREEN (3400 3500);
DISPLAY INVISIBLE (3400 3500);
FORCEPROP 1 LAST HDL_TAP TRUE
J 0
(3725 3325);
DISPLAY 0.872340 (3725 3325);
DISPLAY INVISIBLE (3725 3325);
FORCEPROP 1 LAST PATH I149
J 0
(3398 3450);
DISPLAY 0.872340 (3398 3450);
PAINT GREEN (3398 3450);
DISPLAY INVISIBLE (3398 3450);
FORCEADD OFFPAGE..3
R 2
(-1050 1925);
FORCEPROP 2 LAST $XR1 89 
J 0
(-1419 1925);
DISPLAY 0.638298 (-1419 1925);
PAINT MONO (-1419 1925);
FORCEPROP 2 LAST $XR0 88 
J 0
(-1329 1925);
DISPLAY 0.638298 (-1329 1925);
PAINT MONO (-1329 1925);
FORCEPROP 2 LAST CDS_LIB standard
J 0
(-1050 1925);
DISPLAY INVISIBLE (-1050 1925);
FORCEPROP 1 LAST OFFPAGE TRUE
J 2
(-1375 1800);
DISPLAY 0.872340 (-1375 1800);
DISPLAY INVISIBLE (-1375 1800);
FORCEPROP 1 LAST COMMENT_BODY TRUE
J 2
(-1000 1825);
DISPLAY 0.872340 (-1000 1825);
PAINT GREEN (-1000 1825);
DISPLAY INVISIBLE (-1000 1825);
FORCEPROP 2 LAST PATH I15
J 0
(-1000 2000);
DISPLAY 1.021277 (-1000 2000);
DISPLAY INVISIBLE (-1000 2000);
FORCEADD TAP..1
(3400 3500);
FORCEPROP 3 LASTPIN (3350 3500) SIG_NAME M_D_CPU0_SA_DQS_DP<1>
J 0
(3360 3510);
DISPLAY 0.659574 (3360 3510);
PAINT MONO (3360 3510);
DISPLAY INVISIBLE (3360 3510);
FORCEPROP 1 LASTPIN (3350 3500) BN 1
J 0
(3338 3508);
DISPLAY 0.680851 (3338 3508);
PAINT GREEN (3338 3508);
FORCEPROP 2 LAST CDS_LIB standard
J 0
(3400 3500);
DISPLAY INVISIBLE (3400 3500);
FORCEPROP 1 LAST BODY_TYPE PLUMBING
J 0
(3400 3550);
DISPLAY 0.872340 (3400 3550);
PAINT GREEN (3400 3550);
DISPLAY INVISIBLE (3400 3550);
FORCEPROP 1 LAST HDL_TAP TRUE
J 0
(3725 3375);
DISPLAY 0.872340 (3725 3375);
DISPLAY INVISIBLE (3725 3375);
FORCEPROP 1 LAST PATH I150
J 0
(3398 3500);
DISPLAY 0.872340 (3398 3500);
PAINT GREEN (3398 3500);
DISPLAY INVISIBLE (3398 3500);
FORCEADD TAP..1
(3400 3600);
FORCEPROP 3 LASTPIN (3350 3600) SIG_NAME M_D_CPU0_SA_DQS_DP<3>
J 0
(3360 3610);
DISPLAY 0.659574 (3360 3610);
PAINT MONO (3360 3610);
DISPLAY INVISIBLE (3360 3610);
FORCEPROP 1 LASTPIN (3350 3600) BN 3
J 0
(3338 3608);
DISPLAY 0.680851 (3338 3608);
PAINT GREEN (3338 3608);
FORCEPROP 2 LAST CDS_LIB standard
J 0
(3400 3600);
DISPLAY INVISIBLE (3400 3600);
FORCEPROP 1 LAST BODY_TYPE PLUMBING
J 0
(3400 3650);
DISPLAY 0.872340 (3400 3650);
PAINT GREEN (3400 3650);
DISPLAY INVISIBLE (3400 3650);
FORCEPROP 1 LAST HDL_TAP TRUE
J 0
(3725 3475);
DISPLAY 0.872340 (3725 3475);
DISPLAY INVISIBLE (3725 3475);
FORCEPROP 1 LAST PATH I151
J 0
(3398 3600);
DISPLAY 0.872340 (3398 3600);
PAINT GREEN (3398 3600);
DISPLAY INVISIBLE (3398 3600);
FORCEADD TAP..1
(3400 3550);
FORCEPROP 3 LASTPIN (3350 3550) SIG_NAME M_D_CPU0_SA_DQS_DP<2>
J 0
(3360 3560);
DISPLAY 0.659574 (3360 3560);
PAINT MONO (3360 3560);
DISPLAY INVISIBLE (3360 3560);
FORCEPROP 1 LASTPIN (3350 3550) BN 2
J 0
(3338 3558);
DISPLAY 0.680851 (3338 3558);
PAINT GREEN (3338 3558);
FORCEPROP 2 LAST CDS_LIB standard
J 0
(3400 3550);
DISPLAY INVISIBLE (3400 3550);
FORCEPROP 1 LAST BODY_TYPE PLUMBING
J 0
(3400 3600);
DISPLAY 0.872340 (3400 3600);
PAINT GREEN (3400 3600);
DISPLAY INVISIBLE (3400 3600);
FORCEPROP 1 LAST HDL_TAP TRUE
J 0
(3725 3425);
DISPLAY 0.872340 (3725 3425);
DISPLAY INVISIBLE (3725 3425);
FORCEPROP 1 LAST PATH I152
J 0
(3398 3550);
DISPLAY 0.872340 (3398 3550);
PAINT GREEN (3398 3550);
DISPLAY INVISIBLE (3398 3550);
FORCEADD TAP..1
(3400 3700);
FORCEPROP 3 LASTPIN (3350 3700) SIG_NAME M_D_CPU0_SA_DQS_DP<5>
J 0
(3360 3710);
DISPLAY 0.659574 (3360 3710);
PAINT MONO (3360 3710);
DISPLAY INVISIBLE (3360 3710);
FORCEPROP 1 LASTPIN (3350 3700) BN 5
J 0
(3338 3708);
DISPLAY 0.680851 (3338 3708);
PAINT GREEN (3338 3708);
FORCEPROP 2 LAST CDS_LIB standard
J 0
(3400 3700);
DISPLAY INVISIBLE (3400 3700);
FORCEPROP 1 LAST BODY_TYPE PLUMBING
J 0
(3400 3750);
DISPLAY 0.872340 (3400 3750);
PAINT GREEN (3400 3750);
DISPLAY INVISIBLE (3400 3750);
FORCEPROP 1 LAST HDL_TAP TRUE
J 0
(3725 3575);
DISPLAY 0.872340 (3725 3575);
DISPLAY INVISIBLE (3725 3575);
FORCEPROP 1 LAST PATH I153
J 0
(3398 3700);
DISPLAY 0.872340 (3398 3700);
PAINT GREEN (3398 3700);
DISPLAY INVISIBLE (3398 3700);
FORCEADD TAP..1
(3400 3650);
FORCEPROP 3 LASTPIN (3350 3650) SIG_NAME M_D_CPU0_SA_DQS_DP<4>
J 0
(3360 3660);
DISPLAY 0.659574 (3360 3660);
PAINT MONO (3360 3660);
DISPLAY INVISIBLE (3360 3660);
FORCEPROP 1 LASTPIN (3350 3650) BN 4
J 0
(3338 3658);
DISPLAY 0.680851 (3338 3658);
PAINT GREEN (3338 3658);
FORCEPROP 2 LAST CDS_LIB standard
J 0
(3400 3650);
DISPLAY INVISIBLE (3400 3650);
FORCEPROP 1 LAST BODY_TYPE PLUMBING
J 0
(3400 3700);
DISPLAY 0.872340 (3400 3700);
PAINT GREEN (3400 3700);
DISPLAY INVISIBLE (3400 3700);
FORCEPROP 1 LAST HDL_TAP TRUE
J 0
(3725 3525);
DISPLAY 0.872340 (3725 3525);
DISPLAY INVISIBLE (3725 3525);
FORCEPROP 1 LAST PATH I154
J 0
(3398 3650);
DISPLAY 0.872340 (3398 3650);
PAINT GREEN (3398 3650);
DISPLAY INVISIBLE (3398 3650);
FORCEADD TAP..1
(3400 3750);
FORCEPROP 3 LASTPIN (3350 3750) SIG_NAME M_D_CPU0_SA_DQS_DP<6>
J 0
(3360 3760);
DISPLAY 0.659574 (3360 3760);
PAINT MONO (3360 3760);
DISPLAY INVISIBLE (3360 3760);
FORCEPROP 1 LASTPIN (3350 3750) BN 6
J 0
(3338 3758);
DISPLAY 0.680851 (3338 3758);
PAINT GREEN (3338 3758);
FORCEPROP 2 LAST CDS_LIB standard
J 0
(3400 3750);
DISPLAY INVISIBLE (3400 3750);
FORCEPROP 1 LAST BODY_TYPE PLUMBING
J 0
(3400 3800);
DISPLAY 0.872340 (3400 3800);
PAINT GREEN (3400 3800);
DISPLAY INVISIBLE (3400 3800);
FORCEPROP 1 LAST HDL_TAP TRUE
J 0
(3725 3625);
DISPLAY 0.872340 (3725 3625);
DISPLAY INVISIBLE (3725 3625);
FORCEPROP 1 LAST PATH I155
J 0
(3398 3750);
DISPLAY 0.872340 (3398 3750);
PAINT GREEN (3398 3750);
DISPLAY INVISIBLE (3398 3750);
FORCEADD TAP..1
(3400 3800);
FORCEPROP 3 LASTPIN (3350 3800) SIG_NAME M_D_CPU0_SA_DQS_DP<7>
J 0
(3360 3810);
DISPLAY 0.659574 (3360 3810);
PAINT MONO (3360 3810);
DISPLAY INVISIBLE (3360 3810);
FORCEPROP 1 LASTPIN (3350 3800) BN 7
J 0
(3338 3808);
DISPLAY 0.680851 (3338 3808);
PAINT GREEN (3338 3808);
FORCEPROP 2 LAST CDS_LIB standard
J 0
(3400 3800);
DISPLAY INVISIBLE (3400 3800);
FORCEPROP 1 LAST BODY_TYPE PLUMBING
J 0
(3400 3850);
DISPLAY 0.872340 (3400 3850);
PAINT GREEN (3400 3850);
DISPLAY INVISIBLE (3400 3850);
FORCEPROP 1 LAST HDL_TAP TRUE
J 0
(3725 3675);
DISPLAY 0.872340 (3725 3675);
DISPLAY INVISIBLE (3725 3675);
FORCEPROP 1 LAST PATH I156
J 0
(3398 3800);
DISPLAY 0.872340 (3398 3800);
PAINT GREEN (3398 3800);
DISPLAY INVISIBLE (3398 3800);
FORCEADD TAP..1
(3400 3850);
FORCEPROP 3 LASTPIN (3350 3850) SIG_NAME M_D_CPU0_SA_DQS_DP<8>
J 0
(3360 3860);
DISPLAY 0.659574 (3360 3860);
PAINT MONO (3360 3860);
DISPLAY INVISIBLE (3360 3860);
FORCEPROP 1 LASTPIN (3350 3850) BN 8
J 0
(3338 3858);
DISPLAY 0.680851 (3338 3858);
PAINT GREEN (3338 3858);
FORCEPROP 2 LAST CDS_LIB standard
J 0
(3400 3850);
DISPLAY INVISIBLE (3400 3850);
FORCEPROP 1 LAST BODY_TYPE PLUMBING
J 0
(3400 3900);
DISPLAY 0.872340 (3400 3900);
PAINT GREEN (3400 3900);
DISPLAY INVISIBLE (3400 3900);
FORCEPROP 1 LAST HDL_TAP TRUE
J 0
(3725 3725);
DISPLAY 0.872340 (3725 3725);
DISPLAY INVISIBLE (3725 3725);
FORCEPROP 1 LAST PATH I157
J 0
(3398 3850);
DISPLAY 0.872340 (3398 3850);
PAINT GREEN (3398 3850);
DISPLAY INVISIBLE (3398 3850);
FORCEADD TAP..1
(3400 3900);
FORCEPROP 3 LASTPIN (3350 3900) SIG_NAME M_D_CPU0_SA_DQS_DP<9>
J 0
(3360 3910);
DISPLAY 0.659574 (3360 3910);
PAINT MONO (3360 3910);
DISPLAY INVISIBLE (3360 3910);
FORCEPROP 1 LASTPIN (3350 3900) BN 9
J 0
(3338 3908);
DISPLAY 0.680851 (3338 3908);
PAINT GREEN (3338 3908);
FORCEPROP 2 LAST CDS_LIB standard
J 0
(3400 3900);
DISPLAY INVISIBLE (3400 3900);
FORCEPROP 1 LAST BODY_TYPE PLUMBING
J 0
(3400 3950);
DISPLAY 0.872340 (3400 3950);
PAINT GREEN (3400 3950);
DISPLAY INVISIBLE (3400 3950);
FORCEPROP 1 LAST HDL_TAP TRUE
J 0
(3725 3775);
DISPLAY 0.872340 (3725 3775);
DISPLAY INVISIBLE (3725 3775);
FORCEPROP 1 LAST PATH I158
J 0
(3398 3900);
DISPLAY 0.872340 (3398 3900);
PAINT GREEN (3398 3900);
DISPLAY INVISIBLE (3398 3900);
FORCEADD OFFPAGE..2
(4500 325);
FORCEPROP 2 LAST $XR1 89 
J 0
(4779 325);
DISPLAY 0.638298 (4779 325);
PAINT MONO (4779 325);
FORCEPROP 2 LAST $XR0 88 
J 0
(4689 325);
DISPLAY 0.638298 (4689 325);
PAINT MONO (4689 325);
FORCEPROP 2 LAST CDS_LIB standard
J 0
(4500 325);
PAINT MONO (4500 325);
DISPLAY INVISIBLE (4500 325);
FORCEPROP 1 LAST OFFPAGE TRUE
J 0
(4825 200);
DISPLAY 1.170213 (4825 200);
PAINT GREEN (4825 200);
DISPLAY INVISIBLE (4825 200);
FORCEPROP 1 LAST COMMENT_BODY TRUE
J 0
(4455 230);
DISPLAY 1.170213 (4455 230);
PAINT GREEN (4455 230);
DISPLAY INVISIBLE (4455 230);
FORCEPROP 2 LAST PATH I159
J 0
(4675 400);
DISPLAY 1.021277 (4675 400);
DISPLAY INVISIBLE (4675 400);
FORCEADD OFFPAGE..3
R 2
(-1050 2325);
FORCEPROP 2 LAST $XR1 89 
J 0
(-1419 2325);
DISPLAY 0.638298 (-1419 2325);
PAINT MONO (-1419 2325);
FORCEPROP 2 LAST $XR0 88 
J 0
(-1329 2325);
DISPLAY 0.638298 (-1329 2325);
PAINT MONO (-1329 2325);
FORCEPROP 2 LAST CDS_LIB standard
J 0
(-1050 2325);
DISPLAY INVISIBLE (-1050 2325);
FORCEPROP 1 LAST OFFPAGE TRUE
J 2
(-1375 2200);
DISPLAY 0.872340 (-1375 2200);
DISPLAY INVISIBLE (-1375 2200);
FORCEPROP 1 LAST COMMENT_BODY TRUE
J 2
(-1000 2225);
DISPLAY 0.872340 (-1000 2225);
PAINT GREEN (-1000 2225);
DISPLAY INVISIBLE (-1000 2225);
FORCEPROP 2 LAST PATH I16
J 0
(-1000 2400);
DISPLAY 1.021277 (-1000 2400);
DISPLAY INVISIBLE (-1000 2400);
FORCEADD OFFPAGE..2
(4500 750);
FORCEPROP 2 LAST $XR1 89 
J 0
(4779 750);
DISPLAY 0.638298 (4779 750);
PAINT MONO (4779 750);
FORCEPROP 2 LAST $XR0 88 
J 0
(4689 750);
DISPLAY 0.638298 (4689 750);
PAINT MONO (4689 750);
FORCEPROP 2 LAST CDS_LIB standard
J 0
(4500 750);
PAINT MONO (4500 750);
DISPLAY INVISIBLE (4500 750);
FORCEPROP 1 LAST OFFPAGE TRUE
J 0
(4825 625);
DISPLAY 1.170213 (4825 625);
PAINT GREEN (4825 625);
DISPLAY INVISIBLE (4825 625);
FORCEPROP 1 LAST COMMENT_BODY TRUE
J 0
(4455 655);
DISPLAY 1.170213 (4455 655);
PAINT GREEN (4455 655);
DISPLAY INVISIBLE (4455 655);
FORCEPROP 2 LAST PATH I160
J 0
(4675 825);
DISPLAY 1.021277 (4675 825);
DISPLAY INVISIBLE (4675 825);
FORCEADD OFFPAGE..2
(4500 625);
FORCEPROP 2 LAST $XR1 89 
J 0
(4779 625);
DISPLAY 0.638298 (4779 625);
PAINT MONO (4779 625);
FORCEPROP 2 LAST $XR0 88 
J 0
(4689 625);
DISPLAY 0.638298 (4689 625);
PAINT MONO (4689 625);
FORCEPROP 2 LAST CDS_LIB standard
J 0
(4500 625);
PAINT MONO (4500 625);
DISPLAY INVISIBLE (4500 625);
FORCEPROP 1 LAST OFFPAGE TRUE
J 0
(4825 500);
DISPLAY 1.170213 (4825 500);
PAINT GREEN (4825 500);
DISPLAY INVISIBLE (4825 500);
FORCEPROP 1 LAST COMMENT_BODY TRUE
J 0
(4455 530);
DISPLAY 1.170213 (4455 530);
PAINT GREEN (4455 530);
DISPLAY INVISIBLE (4455 530);
FORCEPROP 2 LAST PATH I161
J 0
(4675 700);
DISPLAY 1.021277 (4675 700);
DISPLAY INVISIBLE (4675 700);
FORCEADD OFFPAGE..2
(4500 1250);
FORCEPROP 2 LAST $XR1 89 
J 0
(4779 1250);
DISPLAY 0.638298 (4779 1250);
PAINT MONO (4779 1250);
FORCEPROP 2 LAST $XR0 88 
J 0
(4689 1250);
DISPLAY 0.638298 (4689 1250);
PAINT MONO (4689 1250);
FORCEPROP 2 LAST CDS_LIB standard
J 0
(4500 1250);
PAINT MONO (4500 1250);
DISPLAY INVISIBLE (4500 1250);
FORCEPROP 1 LAST OFFPAGE TRUE
J 0
(4825 1125);
DISPLAY 1.170213 (4825 1125);
PAINT GREEN (4825 1125);
DISPLAY INVISIBLE (4825 1125);
FORCEPROP 1 LAST COMMENT_BODY TRUE
J 0
(4455 1155);
DISPLAY 1.170213 (4455 1155);
PAINT GREEN (4455 1155);
DISPLAY INVISIBLE (4455 1155);
FORCEPROP 2 LAST PATH I162
J 0
(4675 1325);
DISPLAY 1.021277 (4675 1325);
DISPLAY INVISIBLE (4675 1325);
FORCEADD OFFPAGE..3
(4500 1125);
FORCEPROP 2 LAST $XR1 89 
J 0
(4804 1125);
DISPLAY 0.638298 (4804 1125);
PAINT MONO (4804 1125);
FORCEPROP 2 LAST $XR0 88 
J 0
(4714 1125);
DISPLAY 0.638298 (4714 1125);
PAINT MONO (4714 1125);
FORCEPROP 2 LAST CDS_LIB standard
J 2
(4500 1125);
DISPLAY INVISIBLE (4500 1125);
FORCEPROP 1 LAST OFFPAGE TRUE
J 0
(4825 1000);
DISPLAY 0.872340 (4825 1000);
DISPLAY INVISIBLE (4825 1000);
FORCEPROP 1 LAST COMMENT_BODY TRUE
J 0
(4450 1025);
DISPLAY 0.872340 (4450 1025);
PAINT GREEN (4450 1025);
DISPLAY INVISIBLE (4450 1025);
FORCEPROP 2 LAST PATH I163
J 0
(4700 1200);
DISPLAY 1.021277 (4700 1200);
DISPLAY INVISIBLE (4700 1200);
FORCEADD OFFPAGE..3
(4500 1625);
FORCEPROP 2 LAST $XR1 89 
J 0
(4804 1625);
DISPLAY 0.638298 (4804 1625);
PAINT MONO (4804 1625);
FORCEPROP 2 LAST $XR0 88 
J 0
(4714 1625);
DISPLAY 0.638298 (4714 1625);
PAINT MONO (4714 1625);
FORCEPROP 2 LAST CDS_LIB standard
J 2
(4500 1625);
DISPLAY INVISIBLE (4500 1625);
FORCEPROP 1 LAST OFFPAGE TRUE
J 0
(4825 1500);
DISPLAY 0.872340 (4825 1500);
DISPLAY INVISIBLE (4825 1500);
FORCEPROP 1 LAST COMMENT_BODY TRUE
J 0
(4450 1525);
DISPLAY 0.872340 (4450 1525);
PAINT GREEN (4450 1525);
DISPLAY INVISIBLE (4450 1525);
FORCEPROP 2 LAST PATH I164
J 0
(4700 1700);
DISPLAY 1.021277 (4700 1700);
DISPLAY INVISIBLE (4700 1700);
FORCEADD OFFPAGE..3
(4500 2225);
FORCEPROP 2 LAST $XR1 89 
J 0
(4804 2225);
DISPLAY 0.638298 (4804 2225);
PAINT MONO (4804 2225);
FORCEPROP 2 LAST $XR0 88 
J 0
(4714 2225);
DISPLAY 0.638298 (4714 2225);
PAINT MONO (4714 2225);
FORCEPROP 2 LAST CDS_LIB standard
J 2
(4500 2225);
DISPLAY INVISIBLE (4500 2225);
FORCEPROP 1 LAST OFFPAGE TRUE
J 0
(4825 2100);
DISPLAY 0.872340 (4825 2100);
DISPLAY INVISIBLE (4825 2100);
FORCEPROP 1 LAST COMMENT_BODY TRUE
J 0
(4450 2125);
DISPLAY 0.872340 (4450 2125);
PAINT GREEN (4450 2125);
DISPLAY INVISIBLE (4450 2125);
FORCEPROP 2 LAST PATH I165
J 0
(4700 2300);
DISPLAY 1.021277 (4700 2300);
DISPLAY INVISIBLE (4700 2300);
FORCEADD OFFPAGE..3
(4500 2775);
FORCEPROP 2 LAST $XR1 89 
J 0
(4804 2775);
DISPLAY 0.638298 (4804 2775);
PAINT MONO (4804 2775);
FORCEPROP 2 LAST $XR0 88 
J 0
(4714 2775);
DISPLAY 0.638298 (4714 2775);
PAINT MONO (4714 2775);
FORCEPROP 2 LAST CDS_LIB standard
J 2
(4500 2775);
DISPLAY INVISIBLE (4500 2775);
FORCEPROP 1 LAST OFFPAGE TRUE
J 0
(4825 2650);
DISPLAY 0.872340 (4825 2650);
DISPLAY INVISIBLE (4825 2650);
FORCEPROP 1 LAST COMMENT_BODY TRUE
J 0
(4450 2675);
DISPLAY 0.872340 (4450 2675);
PAINT GREEN (4450 2675);
DISPLAY INVISIBLE (4450 2675);
FORCEPROP 2 LAST PATH I166
J 0
(4700 2850);
DISPLAY 1.021277 (4700 2850);
DISPLAY INVISIBLE (4700 2850);
FORCEADD OFFPAGE..3
(4500 3375);
FORCEPROP 2 LAST $XR1 89 
J 0
(4804 3375);
DISPLAY 0.638298 (4804 3375);
PAINT MONO (4804 3375);
FORCEPROP 2 LAST $XR0 88 
J 0
(4714 3375);
DISPLAY 0.638298 (4714 3375);
PAINT MONO (4714 3375);
FORCEPROP 2 LAST CDS_LIB standard
J 2
(4500 3375);
DISPLAY INVISIBLE (4500 3375);
FORCEPROP 1 LAST OFFPAGE TRUE
J 0
(4825 3250);
DISPLAY 0.872340 (4825 3250);
DISPLAY INVISIBLE (4825 3250);
FORCEPROP 1 LAST COMMENT_BODY TRUE
J 0
(4450 3275);
DISPLAY 0.872340 (4450 3275);
PAINT GREEN (4450 3275);
DISPLAY INVISIBLE (4450 3275);
FORCEPROP 2 LAST PATH I167
J 0
(4700 3450);
DISPLAY 1.021277 (4700 3450);
DISPLAY INVISIBLE (4700 3450);
FORCEADD OFFPAGE..3
(4500 3925);
FORCEPROP 2 LAST $XR1 89 
J 0
(4804 3925);
DISPLAY 0.638298 (4804 3925);
PAINT MONO (4804 3925);
FORCEPROP 2 LAST $XR0 88 
J 0
(4714 3925);
DISPLAY 0.638298 (4714 3925);
PAINT MONO (4714 3925);
FORCEPROP 2 LAST CDS_LIB standard
J 2
(4500 3925);
DISPLAY INVISIBLE (4500 3925);
FORCEPROP 1 LAST OFFPAGE TRUE
J 0
(4825 3800);
DISPLAY 0.872340 (4825 3800);
DISPLAY INVISIBLE (4825 3800);
FORCEPROP 1 LAST COMMENT_BODY TRUE
J 0
(4450 3825);
DISPLAY 0.872340 (4450 3825);
PAINT GREEN (4450 3825);
DISPLAY INVISIBLE (4450 3825);
FORCEPROP 2 LAST PATH I168
J 0
(4700 4000);
DISPLAY 1.021277 (4700 4000);
DISPLAY INVISIBLE (4700 4000);
FORCEADD SOCKET4677_AZIF0045P001C01CS..11
(1700 1800);
FORCEPROP 1 LAST PART_NUMBER DGA^7000023
J 0
(600 4150);
DISPLAY 0.723404 (600 4150);
PAINT GREEN (600 4150);
DISPLAY INVISIBLE (600 4150);
FORCEPROP 2 LAST PART_TYPE SMLF
J 0
(600 4325);
DISPLAY 1.021277 (600 4325);
FORCEPROP 1 LAST MATERIAL IO
J 0
(600 4075);
DISPLAY 0.723404 (600 4075);
PAINT GREEN (600 4075);
FORCEPROP 2 LAST VALUE SOCKET4677_AZIF0045-P001C01CS
J 0
(600 4275);
DISPLAY 1.021277 (600 4275);
FORCEPROP 1 LAST $LOCATION U2
J 0
(600 4225);
DISPLAY 0.723404 (600 4225);
PAINT GREEN (600 4225);
FORCEPROP 0 LASTPIN (2925 -50) $PN AD51
J 0
(2935 -40);
DISPLAY 0.680851 (2935 -40);
PAINT MONO (2935 -40);
FORCEPROP 0 LASTPIN (2925 0) $PN AC50
J 0
(2935 10);
DISPLAY 0.680851 (2935 10);
PAINT MONO (2935 10);
FORCEPROP 0 LASTPIN (2925 -300) $PN AV47
J 0
(2935 -290);
DISPLAY 0.680851 (2935 -290);
PAINT MONO (2935 -290);
FORCEPROP 0 LASTPIN (2925 -200) $PN AF51
J 0
(2935 -190);
DISPLAY 0.680851 (2935 -190);
PAINT MONO (2935 -190);
FORCEPROP 0 LASTPIN (2925 -150) $PN AG50
J 0
(2935 -140);
DISPLAY 0.680851 (2935 -140);
PAINT MONO (2935 -140);
FORCEPROP 0 LASTPIN (475 -300) $PN AJ45
J 2
(465 -290);
DISPLAY 0.680851 (465 -290);
PAINT MONO (465 -290);
FORCEPROP 0 LASTPIN (475 -250) $PN AN45
J 2
(465 -240);
DISPLAY 0.680851 (465 -240);
PAINT MONO (465 -240);
FORCEPROP 0 LASTPIN (475 -200) $PN AL45
J 2
(465 -190);
DISPLAY 0.680851 (465 -190);
PAINT MONO (465 -190);
FORCEPROP 0 LASTPIN (475 -150) $PN AR45
J 2
(465 -140);
DISPLAY 0.680851 (465 -140);
PAINT MONO (465 -140);
FORCEPROP 0 LASTPIN (2925 1300) $PN AJ52
J 0
(2935 1310);
DISPLAY 0.680851 (2935 1310);
PAINT MONO (2935 1310);
FORCEPROP 0 LASTPIN (2925 1350) $PN AR52
J 0
(2935 1360);
DISPLAY 0.680851 (2935 1360);
PAINT MONO (2935 1360);
FORCEPROP 0 LASTPIN (2925 1400) $PN AK51
J 0
(2935 1410);
DISPLAY 0.680851 (2935 1410);
PAINT MONO (2935 1410);
FORCEPROP 0 LASTPIN (2925 1450) $PN AP51
J 0
(2935 1460);
DISPLAY 0.680851 (2935 1460);
PAINT MONO (2935 1460);
FORCEPROP 0 LASTPIN (2925 1500) $PN AL50
J 0
(2935 1510);
DISPLAY 0.680851 (2935 1510);
PAINT MONO (2935 1510);
FORCEPROP 0 LASTPIN (2925 1550) $PN AN50
J 0
(2935 1560);
DISPLAY 0.680851 (2935 1560);
PAINT MONO (2935 1560);
FORCEPROP 0 LASTPIN (2925 1600) $PN AN43
J 0
(2935 1610);
DISPLAY 0.680851 (2935 1610);
PAINT MONO (2935 1610);
FORCEPROP 0 LASTPIN (475 2350) $PN AD75
J 2
(465 2360);
DISPLAY 0.680851 (465 2360);
PAINT MONO (465 2360);
FORCEPROP 0 LASTPIN (475 2400) $PN AC74
J 2
(465 2410);
DISPLAY 0.680851 (465 2410);
PAINT MONO (465 2410);
FORCEPROP 0 LASTPIN (475 2450) $PN AF75
J 2
(465 2460);
DISPLAY 0.680851 (465 2460);
PAINT MONO (465 2460);
FORCEPROP 0 LASTPIN (475 2500) $PN AG74
J 2
(465 2510);
DISPLAY 0.680851 (465 2510);
PAINT MONO (465 2510);
FORCEPROP 0 LASTPIN (475 2550) $PN AC72
J 2
(465 2560);
DISPLAY 0.680851 (465 2560);
PAINT MONO (465 2560);
FORCEPROP 0 LASTPIN (475 2600) $PN AD71
J 2
(465 2610);
DISPLAY 0.680851 (465 2610);
PAINT MONO (465 2610);
FORCEPROP 0 LASTPIN (475 2650) $PN AG72
J 2
(465 2660);
DISPLAY 0.680851 (465 2660);
PAINT MONO (465 2660);
FORCEPROP 0 LASTPIN (475 2700) $PN AF71
J 2
(465 2710);
DISPLAY 0.680851 (465 2710);
PAINT MONO (465 2710);
FORCEPROP 0 LASTPIN (475 2750) $PN AL78
J 2
(465 2760);
DISPLAY 0.680851 (465 2760);
PAINT MONO (465 2760);
FORCEPROP 0 LASTPIN (475 2800) $PN AK77
J 2
(465 2810);
DISPLAY 0.680851 (465 2810);
PAINT MONO (465 2810);
FORCEPROP 0 LASTPIN (475 2850) $PN AN78
J 2
(465 2860);
DISPLAY 0.680851 (465 2860);
PAINT MONO (465 2860);
FORCEPROP 0 LASTPIN (475 2900) $PN AP77
J 2
(465 2910);
DISPLAY 0.680851 (465 2910);
PAINT MONO (465 2910);
FORCEPROP 0 LASTPIN (475 2950) $PN AK75
J 2
(465 2960);
DISPLAY 0.680851 (465 2960);
PAINT MONO (465 2960);
FORCEPROP 0 LASTPIN (475 3000) $PN AL74
J 2
(465 3010);
DISPLAY 0.680851 (465 3010);
PAINT MONO (465 3010);
FORCEPROP 0 LASTPIN (475 3050) $PN AP75
J 2
(465 3060);
DISPLAY 0.680851 (465 3060);
PAINT MONO (465 3060);
FORCEPROP 0 LASTPIN (475 3100) $PN AN74
J 2
(465 3110);
DISPLAY 0.680851 (465 3110);
PAINT MONO (465 3110);
FORCEPROP 0 LASTPIN (475 3150) $PN AL72
J 2
(465 3160);
DISPLAY 0.680851 (465 3160);
PAINT MONO (465 3160);
FORCEPROP 0 LASTPIN (475 3200) $PN AK71
J 2
(465 3210);
DISPLAY 0.680851 (465 3210);
PAINT MONO (465 3210);
FORCEPROP 0 LASTPIN (475 3250) $PN AN72
J 2
(465 3260);
DISPLAY 0.680851 (465 3260);
PAINT MONO (465 3260);
FORCEPROP 0 LASTPIN (475 3300) $PN AP71
J 2
(465 3310);
DISPLAY 0.680851 (465 3310);
PAINT MONO (465 3310);
FORCEPROP 0 LASTPIN (475 3350) $PN AK69
J 2
(465 3360);
DISPLAY 0.680851 (465 3360);
PAINT MONO (465 3360);
FORCEPROP 0 LASTPIN (475 3400) $PN AL68
J 2
(465 3410);
DISPLAY 0.680851 (465 3410);
PAINT MONO (465 3410);
FORCEPROP 0 LASTPIN (475 3450) $PN AP69
J 2
(465 3460);
DISPLAY 0.680851 (465 3460);
PAINT MONO (465 3460);
FORCEPROP 0 LASTPIN (475 3500) $PN AN68
J 2
(465 3510);
DISPLAY 0.680851 (465 3510);
PAINT MONO (465 3510);
FORCEPROP 0 LASTPIN (475 3550) $PN AL66
J 2
(465 3560);
DISPLAY 0.680851 (465 3560);
PAINT MONO (465 3560);
FORCEPROP 0 LASTPIN (475 3600) $PN AK65
J 2
(465 3610);
DISPLAY 0.680851 (465 3610);
PAINT MONO (465 3610);
FORCEPROP 0 LASTPIN (475 3650) $PN AN66
J 2
(465 3660);
DISPLAY 0.680851 (465 3660);
PAINT MONO (465 3660);
FORCEPROP 0 LASTPIN (475 3700) $PN AP65
J 2
(465 3710);
DISPLAY 0.680851 (465 3710);
PAINT MONO (465 3710);
FORCEPROP 0 LASTPIN (475 3750) $PN AK63
J 2
(465 3760);
DISPLAY 0.680851 (465 3760);
PAINT MONO (465 3760);
FORCEPROP 0 LASTPIN (475 3800) $PN AL62
J 2
(465 3810);
DISPLAY 0.680851 (465 3810);
PAINT MONO (465 3810);
FORCEPROP 0 LASTPIN (475 3850) $PN AP63
J 2
(465 3860);
DISPLAY 0.680851 (465 3860);
PAINT MONO (465 3860);
FORCEPROP 0 LASTPIN (475 3900) $PN AN62
J 2
(465 3910);
DISPLAY 0.680851 (465 3910);
PAINT MONO (465 3910);
FORCEPROP 0 LASTPIN (2925 2900) $PN AB73
J 0
(2935 2910);
DISPLAY 0.680851 (2935 2910);
PAINT MONO (2935 2910);
FORCEPROP 0 LASTPIN (2925 2950) $PN AJ76
J 0
(2935 2960);
DISPLAY 0.680851 (2935 2960);
PAINT MONO (2935 2960);
FORCEPROP 0 LASTPIN (2925 3000) $PN AJ70
J 0
(2935 3010);
DISPLAY 0.680851 (2935 3010);
PAINT MONO (2935 3010);
FORCEPROP 0 LASTPIN (2925 3050) $PN AJ64
J 0
(2935 3060);
DISPLAY 0.680851 (2935 3060);
PAINT MONO (2935 3060);
FORCEPROP 0 LASTPIN (2925 3100) $PN AJ58
J 0
(2935 3110);
DISPLAY 0.680851 (2935 3110);
PAINT MONO (2935 3110);
FORCEPROP 0 LASTPIN (2925 3150) $PN AH73
J 0
(2935 3160);
DISPLAY 0.680851 (2935 3160);
PAINT MONO (2935 3160);
FORCEPROP 0 LASTPIN (2925 3200) $PN AN76
J 0
(2935 3210);
DISPLAY 0.680851 (2935 3210);
PAINT MONO (2935 3210);
FORCEPROP 0 LASTPIN (2925 3250) $PN AN70
J 0
(2935 3260);
DISPLAY 0.680851 (2935 3260);
PAINT MONO (2935 3260);
FORCEPROP 0 LASTPIN (2925 3300) $PN AN64
J 0
(2935 3310);
DISPLAY 0.680851 (2935 3310);
PAINT MONO (2935 3310);
FORCEPROP 0 LASTPIN (2925 3350) $PN AN58
J 0
(2935 3360);
DISPLAY 0.680851 (2935 3360);
PAINT MONO (2935 3360);
FORCEPROP 0 LASTPIN (2925 3450) $PN AD73
J 0
(2935 3460);
DISPLAY 0.680851 (2935 3460);
PAINT MONO (2935 3460);
FORCEPROP 0 LASTPIN (2925 3500) $PN AL76
J 0
(2935 3510);
DISPLAY 0.680851 (2935 3510);
PAINT MONO (2935 3510);
FORCEPROP 0 LASTPIN (2925 3550) $PN AL70
J 0
(2935 3560);
DISPLAY 0.680851 (2935 3560);
PAINT MONO (2935 3560);
FORCEPROP 0 LASTPIN (2925 3600) $PN AL64
J 0
(2935 3610);
DISPLAY 0.680851 (2935 3610);
PAINT MONO (2935 3610);
FORCEPROP 0 LASTPIN (2925 3650) $PN AL58
J 0
(2935 3660);
DISPLAY 0.680851 (2935 3660);
PAINT MONO (2935 3660);
FORCEPROP 0 LASTPIN (2925 3700) $PN AF73
J 0
(2935 3710);
DISPLAY 0.680851 (2935 3710);
PAINT MONO (2935 3710);
FORCEPROP 0 LASTPIN (2925 3750) $PN AR76
J 0
(2935 3760);
DISPLAY 0.680851 (2935 3760);
PAINT MONO (2935 3760);
FORCEPROP 0 LASTPIN (2925 3800) $PN AR70
J 0
(2935 3810);
DISPLAY 0.680851 (2935 3810);
PAINT MONO (2935 3810);
FORCEPROP 0 LASTPIN (2925 3850) $PN AR64
J 0
(2935 3860);
DISPLAY 0.680851 (2935 3860);
PAINT MONO (2935 3860);
FORCEPROP 0 LASTPIN (2925 3900) $PN AR58
J 0
(2935 3910);
DISPLAY 0.680851 (2935 3910);
PAINT MONO (2935 3910);
FORCEPROP 0 LASTPIN (475 1950) $PN AL60
J 2
(465 1960);
DISPLAY 0.680851 (465 1960);
PAINT MONO (465 1960);
FORCEPROP 0 LASTPIN (475 2000) $PN AK59
J 2
(465 2010);
DISPLAY 0.680851 (465 2010);
PAINT MONO (465 2010);
FORCEPROP 0 LASTPIN (475 2050) $PN AN60
J 2
(465 2060);
DISPLAY 0.680851 (465 2060);
PAINT MONO (465 2060);
FORCEPROP 0 LASTPIN (475 2100) $PN AP59
J 2
(465 2110);
DISPLAY 0.680851 (465 2110);
PAINT MONO (465 2110);
FORCEPROP 0 LASTPIN (475 2150) $PN AK57
J 2
(465 2160);
DISPLAY 0.680851 (465 2160);
PAINT MONO (465 2160);
FORCEPROP 0 LASTPIN (475 2200) $PN AL56
J 2
(465 2210);
DISPLAY 0.680851 (465 2210);
PAINT MONO (465 2210);
FORCEPROP 0 LASTPIN (475 2250) $PN AP57
J 2
(465 2260);
DISPLAY 0.680851 (465 2260);
PAINT MONO (465 2260);
FORCEPROP 0 LASTPIN (475 2300) $PN AN56
J 2
(465 2310);
DISPLAY 0.680851 (465 2310);
PAINT MONO (465 2310);
FORCEPROP 0 LASTPIN (2925 1250) $PN AP44
J 0
(2935 1260);
DISPLAY 0.680851 (2935 1260);
PAINT MONO (2935 1260);
FORCEPROP 0 LASTPIN (2925 800) $PN AK44
J 0
(2935 810);
DISPLAY 0.680851 (2935 810);
PAINT MONO (2935 810);
FORCEPROP 0 LASTPIN (2925 850) $PN AL43
J 0
(2935 860);
DISPLAY 0.680851 (2935 860);
PAINT MONO (2935 860);
FORCEPROP 0 LASTPIN (2925 900) $PN AD44
J 0
(2935 910);
DISPLAY 0.680851 (2935 910);
PAINT MONO (2935 910);
FORCEPROP 0 LASTPIN (2925 950) $PN AF44
J 0
(2935 960);
DISPLAY 0.680851 (2935 960);
PAINT MONO (2935 960);
FORCEPROP 0 LASTPIN (2925 1000) $PN AC43
J 0
(2935 1010);
DISPLAY 0.680851 (2935 1010);
PAINT MONO (2935 1010);
FORCEPROP 0 LASTPIN (2925 1050) $PN AG43
J 0
(2935 1060);
DISPLAY 0.680851 (2935 1060);
PAINT MONO (2935 1060);
FORCEPROP 0 LASTPIN (2925 1100) $PN AB42
J 0
(2935 1110);
DISPLAY 0.680851 (2935 1110);
PAINT MONO (2935 1110);
FORCEPROP 0 LASTPIN (475 350) $PN AL35
J 2
(465 360);
DISPLAY 0.680851 (465 360);
PAINT MONO (465 360);
FORCEPROP 0 LASTPIN (475 400) $PN AK34
J 2
(465 410);
DISPLAY 0.680851 (465 410);
PAINT MONO (465 410);
FORCEPROP 0 LASTPIN (475 450) $PN AN35
J 2
(465 460);
DISPLAY 0.680851 (465 460);
PAINT MONO (465 460);
FORCEPROP 0 LASTPIN (475 500) $PN AP34
J 2
(465 510);
DISPLAY 0.680851 (465 510);
PAINT MONO (465 510);
FORCEPROP 0 LASTPIN (475 550) $PN AK32
J 2
(465 560);
DISPLAY 0.680851 (465 560);
PAINT MONO (465 560);
FORCEPROP 0 LASTPIN (475 600) $PN AL31
J 2
(465 610);
DISPLAY 0.680851 (465 610);
PAINT MONO (465 610);
FORCEPROP 0 LASTPIN (475 650) $PN AP32
J 2
(465 660);
DISPLAY 0.680851 (465 660);
PAINT MONO (465 660);
FORCEPROP 0 LASTPIN (475 700) $PN AN31
J 2
(465 710);
DISPLAY 0.680851 (465 710);
PAINT MONO (465 710);
FORCEPROP 0 LASTPIN (475 750) $PN AL29
J 2
(465 760);
DISPLAY 0.680851 (465 760);
PAINT MONO (465 760);
FORCEPROP 0 LASTPIN (475 800) $PN AK28
J 2
(465 810);
DISPLAY 0.680851 (465 810);
PAINT MONO (465 810);
FORCEPROP 0 LASTPIN (475 850) $PN AN29
J 2
(465 860);
DISPLAY 0.680851 (465 860);
PAINT MONO (465 860);
FORCEPROP 0 LASTPIN (475 900) $PN AP28
J 2
(465 910);
DISPLAY 0.680851 (465 910);
PAINT MONO (465 910);
FORCEPROP 0 LASTPIN (475 950) $PN AK26
J 2
(465 960);
DISPLAY 0.680851 (465 960);
PAINT MONO (465 960);
FORCEPROP 0 LASTPIN (475 1000) $PN AL25
J 2
(465 1010);
DISPLAY 0.680851 (465 1010);
PAINT MONO (465 1010);
FORCEPROP 0 LASTPIN (475 1050) $PN AP26
J 2
(465 1060);
DISPLAY 0.680851 (465 1060);
PAINT MONO (465 1060);
FORCEPROP 0 LASTPIN (475 1100) $PN AN25
J 2
(465 1110);
DISPLAY 0.680851 (465 1110);
PAINT MONO (465 1110);
FORCEPROP 0 LASTPIN (475 1150) $PN AD26
J 2
(465 1160);
DISPLAY 0.680851 (465 1160);
PAINT MONO (465 1160);
FORCEPROP 0 LASTPIN (475 1200) $PN AC25
J 2
(465 1210);
DISPLAY 0.680851 (465 1210);
PAINT MONO (465 1210);
FORCEPROP 0 LASTPIN (475 1250) $PN AF26
J 2
(465 1260);
DISPLAY 0.680851 (465 1260);
PAINT MONO (465 1260);
FORCEPROP 0 LASTPIN (475 1300) $PN AG25
J 2
(465 1310);
DISPLAY 0.680851 (465 1310);
PAINT MONO (465 1310);
FORCEPROP 0 LASTPIN (475 1350) $PN AC23
J 2
(465 1360);
DISPLAY 0.680851 (465 1360);
PAINT MONO (465 1360);
FORCEPROP 0 LASTPIN (475 1400) $PN AD22
J 2
(465 1410);
DISPLAY 0.680851 (465 1410);
PAINT MONO (465 1410);
FORCEPROP 0 LASTPIN (475 1450) $PN AG23
J 2
(465 1460);
DISPLAY 0.680851 (465 1460);
PAINT MONO (465 1460);
FORCEPROP 0 LASTPIN (475 1500) $PN AF22
J 2
(465 1510);
DISPLAY 0.680851 (465 1510);
PAINT MONO (465 1510);
FORCEPROP 0 LASTPIN (475 1550) $PN AL23
J 2
(465 1560);
DISPLAY 0.680851 (465 1560);
PAINT MONO (465 1560);
FORCEPROP 0 LASTPIN (475 1600) $PN AK22
J 2
(465 1610);
DISPLAY 0.680851 (465 1610);
PAINT MONO (465 1610);
FORCEPROP 0 LASTPIN (475 1650) $PN AN23
J 2
(465 1660);
DISPLAY 0.680851 (465 1660);
PAINT MONO (465 1660);
FORCEPROP 0 LASTPIN (475 1700) $PN AP22
J 2
(465 1710);
DISPLAY 0.680851 (465 1710);
PAINT MONO (465 1710);
FORCEPROP 0 LASTPIN (475 1750) $PN AK20
J 2
(465 1760);
DISPLAY 0.680851 (465 1760);
PAINT MONO (465 1760);
FORCEPROP 0 LASTPIN (475 1800) $PN AL19
J 2
(465 1810);
DISPLAY 0.680851 (465 1810);
PAINT MONO (465 1810);
FORCEPROP 0 LASTPIN (475 1850) $PN AP20
J 2
(465 1860);
DISPLAY 0.680851 (465 1860);
PAINT MONO (465 1860);
FORCEPROP 0 LASTPIN (475 1900) $PN AN19
J 2
(465 1910);
DISPLAY 0.680851 (465 1910);
PAINT MONO (465 1910);
FORCEPROP 0 LASTPIN (2925 1750) $PN AJ33
J 0
(2935 1760);
DISPLAY 0.680851 (2935 1760);
PAINT MONO (2935 1760);
FORCEPROP 0 LASTPIN (2925 1800) $PN AJ27
J 0
(2935 1810);
DISPLAY 0.680851 (2935 1810);
PAINT MONO (2935 1810);
FORCEPROP 0 LASTPIN (2925 1850) $PN AB24
J 0
(2935 1860);
DISPLAY 0.680851 (2935 1860);
PAINT MONO (2935 1860);
FORCEPROP 0 LASTPIN (2925 1900) $PN AJ21
J 0
(2935 1910);
DISPLAY 0.680851 (2935 1910);
PAINT MONO (2935 1910);
FORCEPROP 0 LASTPIN (2925 1950) $PN AR39
J 0
(2935 1960);
DISPLAY 0.680851 (2935 1960);
PAINT MONO (2935 1960);
FORCEPROP 0 LASTPIN (2925 2000) $PN AN33
J 0
(2935 2010);
DISPLAY 0.680851 (2935 2010);
PAINT MONO (2935 2010);
FORCEPROP 0 LASTPIN (2925 2050) $PN AN27
J 0
(2935 2060);
DISPLAY 0.680851 (2935 2060);
PAINT MONO (2935 2060);
FORCEPROP 0 LASTPIN (2925 2100) $PN AF24
J 0
(2935 2110);
DISPLAY 0.680851 (2935 2110);
PAINT MONO (2935 2110);
FORCEPROP 0 LASTPIN (2925 2150) $PN AN21
J 0
(2935 2160);
DISPLAY 0.680851 (2935 2160);
PAINT MONO (2935 2160);
FORCEPROP 0 LASTPIN (2925 2200) $PN AJ39
J 0
(2935 2210);
DISPLAY 0.680851 (2935 2210);
PAINT MONO (2935 2210);
FORCEPROP 0 LASTPIN (2925 2300) $PN AL33
J 0
(2935 2310);
DISPLAY 0.680851 (2935 2310);
PAINT MONO (2935 2310);
FORCEPROP 0 LASTPIN (2925 2350) $PN AL27
J 0
(2935 2360);
DISPLAY 0.680851 (2935 2360);
PAINT MONO (2935 2360);
FORCEPROP 0 LASTPIN (2925 2400) $PN AD24
J 0
(2935 2410);
DISPLAY 0.680851 (2935 2410);
PAINT MONO (2935 2410);
FORCEPROP 0 LASTPIN (2925 2450) $PN AL21
J 0
(2935 2460);
DISPLAY 0.680851 (2935 2460);
PAINT MONO (2935 2460);
FORCEPROP 0 LASTPIN (2925 2500) $PN AN39
J 0
(2935 2510);
DISPLAY 0.680851 (2935 2510);
PAINT MONO (2935 2510);
FORCEPROP 0 LASTPIN (2925 2550) $PN AR33
J 0
(2935 2560);
DISPLAY 0.680851 (2935 2560);
PAINT MONO (2935 2560);
FORCEPROP 0 LASTPIN (2925 2600) $PN AR27
J 0
(2935 2610);
DISPLAY 0.680851 (2935 2610);
PAINT MONO (2935 2610);
FORCEPROP 0 LASTPIN (2925 2650) $PN AH24
J 0
(2935 2660);
DISPLAY 0.680851 (2935 2660);
PAINT MONO (2935 2660);
FORCEPROP 0 LASTPIN (2925 2700) $PN AR21
J 0
(2935 2710);
DISPLAY 0.680851 (2935 2710);
PAINT MONO (2935 2710);
FORCEPROP 0 LASTPIN (2925 2750) $PN AL39
J 0
(2935 2760);
DISPLAY 0.680851 (2935 2760);
PAINT MONO (2935 2760);
FORCEPROP 0 LASTPIN (475 -50) $PN AK38
J 2
(465 -40);
DISPLAY 0.680851 (465 -40);
PAINT MONO (465 -40);
FORCEPROP 0 LASTPIN (475 0) $PN AL37
J 2
(465 10);
DISPLAY 0.680851 (465 10);
PAINT MONO (465 10);
FORCEPROP 0 LASTPIN (475 50) $PN AP38
J 2
(465 60);
DISPLAY 0.680851 (465 60);
PAINT MONO (465 60);
FORCEPROP 0 LASTPIN (475 100) $PN AN37
J 2
(465 110);
DISPLAY 0.680851 (465 110);
PAINT MONO (465 110);
FORCEPROP 0 LASTPIN (475 150) $PN AL41
J 2
(465 160);
DISPLAY 0.680851 (465 160);
PAINT MONO (465 160);
FORCEPROP 0 LASTPIN (475 200) $PN AK40
J 2
(465 210);
DISPLAY 0.680851 (465 210);
PAINT MONO (465 210);
FORCEPROP 0 LASTPIN (475 250) $PN AN41
J 2
(465 260);
DISPLAY 0.680851 (465 260);
PAINT MONO (465 260);
FORCEPROP 0 LASTPIN (475 300) $PN AP40
J 2
(465 310);
DISPLAY 0.680851 (465 310);
PAINT MONO (465 310);
FORCEPROP 0 LASTPIN (2925 750) $PN AH42
J 0
(2935 760);
DISPLAY 0.680851 (2935 760);
PAINT MONO (2935 760);
FORCEPROP 0 LASTPIN (2925 450) $PN AL54
J 0
(2935 460);
DISPLAY 0.680851 (2935 460);
PAINT MONO (2935 460);
FORCEPROP 0 LASTPIN (2925 500) $PN AK53
J 0
(2935 510);
DISPLAY 0.680851 (2935 510);
PAINT MONO (2935 510);
FORCEPROP 0 LASTPIN (2925 550) $PN AN54
J 0
(2935 560);
DISPLAY 0.680851 (2935 560);
PAINT MONO (2935 560);
FORCEPROP 0 LASTPIN (2925 600) $PN AP53
J 0
(2935 610);
DISPLAY 0.680851 (2935 610);
PAINT MONO (2935 610);
FORCEPROP 0 LASTPIN (2925 150) $PN AC41
J 0
(2935 160);
DISPLAY 0.680851 (2935 160);
PAINT MONO (2935 160);
FORCEPROP 0 LASTPIN (2925 200) $PN AG41
J 0
(2935 210);
DISPLAY 0.680851 (2935 210);
PAINT MONO (2935 210);
FORCEPROP 0 LASTPIN (2925 250) $PN AF40
J 0
(2935 260);
DISPLAY 0.680851 (2935 260);
PAINT MONO (2935 260);
FORCEPROP 0 LASTPIN (2925 300) $PN AD40
J 0
(2935 310);
DISPLAY 0.680851 (2935 310);
PAINT MONO (2935 310);
FORCEPROP 2 LAST CDS_LIB pure_quanta
J 0
(1700 1800);
DISPLAY INVISIBLE (1700 1800);
FORCEPROP 1 LAST NEEDS_NO_SIZE TRUE
J 0
(1700 1800);
DISPLAY 0.723404 (1700 1800);
PAINT GREEN (1700 1800);
DISPLAY INVISIBLE (1700 1800);
FORCEPROP 1 LAST CDS_LMAN_SYM_OUTLINE -1100,2250,1050,-2250
J 0
(1700 1800);
DISPLAY 0.468085 (1700 1800);
PAINT GREEN (1700 1800);
DISPLAY INVISIBLE (1700 1800);
FORCEPROP 2 LAST CDS_LOCATION U2
J 0
(600 4375);
DISPLAY 1.021277 (600 4375);
DISPLAY INVISIBLE (600 4375);
FORCEPROP 0 LAST $SEC 11
J 0
(600 4375);
DISPLAY 0.680851 (600 4375);
PAINT MONO (600 4375);
DISPLAY INVISIBLE (600 4375);
FORCEPROP 2 LAST CDS_SEC 11
J 0
(600 4375);
DISPLAY 1.021277 (600 4375);
DISPLAY INVISIBLE (600 4375);
FORCEPROP 1 LAST PATH I169
J 0
(1700 1800);
DISPLAY 0.723404 (1700 1800);
PAINT GREEN (1700 1800);
DISPLAY INVISIBLE (1700 1800);
FORCEADD TAP..1
R 2
(-25 300);
FORCEPROP 3 LASTPIN (25 300) SIG_NAME M_D_CPU0_SB_CB<7>
J 0
(35 310);
DISPLAY 0.659574 (35 310);
PAINT MONO (35 310);
DISPLAY INVISIBLE (35 310);
FORCEPROP 1 LASTPIN (25 300) BN 7
J 2
(37 308);
DISPLAY 0.680851 (37 308);
PAINT GREEN (37 308);
FORCEPROP 2 LAST CDS_LIB standard
J 0
(-25 300);
DISPLAY INVISIBLE (-25 300);
FORCEPROP 1 LAST BODY_TYPE PLUMBING
J 2
(-25 350);
DISPLAY 0.872340 (-25 350);
PAINT GREEN (-25 350);
DISPLAY INVISIBLE (-25 350);
FORCEPROP 1 LAST HDL_TAP TRUE
J 2
(-350 175);
DISPLAY 0.872340 (-350 175);
DISPLAY INVISIBLE (-350 175);
FORCEPROP 1 LAST PATH I17
J 2
(-23 300);
DISPLAY 0.872340 (-23 300);
PAINT GREEN (-23 300);
DISPLAY INVISIBLE (-23 300);
FORCEADD TAP..1
R 2
(-25 350);
FORCEPROP 3 LASTPIN (25 350) SIG_NAME M_D_CPU0_SB_DQ<0>
J 0
(35 360);
DISPLAY 0.659574 (35 360);
PAINT MONO (35 360);
DISPLAY INVISIBLE (35 360);
FORCEPROP 1 LASTPIN (25 350) BN 0
J 2
(37 358);
DISPLAY 0.680851 (37 358);
PAINT GREEN (37 358);
FORCEPROP 2 LAST CDS_LIB standard
J 0
(-25 350);
DISPLAY INVISIBLE (-25 350);
FORCEPROP 1 LAST BODY_TYPE PLUMBING
J 2
(-25 400);
DISPLAY 0.872340 (-25 400);
PAINT GREEN (-25 400);
DISPLAY INVISIBLE (-25 400);
FORCEPROP 1 LAST HDL_TAP TRUE
J 2
(-350 225);
DISPLAY 0.872340 (-350 225);
DISPLAY INVISIBLE (-350 225);
FORCEPROP 1 LAST PATH I18
J 2
(-23 350);
DISPLAY 0.872340 (-23 350);
PAINT GREEN (-23 350);
DISPLAY INVISIBLE (-23 350);
FORCEADD TAP..1
R 2
(-25 400);
FORCEPROP 3 LASTPIN (25 400) SIG_NAME M_D_CPU0_SB_DQ<1>
J 0
(35 410);
DISPLAY 0.659574 (35 410);
PAINT MONO (35 410);
DISPLAY INVISIBLE (35 410);
FORCEPROP 1 LASTPIN (25 400) BN 1
J 2
(37 408);
DISPLAY 0.680851 (37 408);
PAINT GREEN (37 408);
FORCEPROP 2 LAST CDS_LIB standard
J 0
(-25 400);
DISPLAY INVISIBLE (-25 400);
FORCEPROP 1 LAST BODY_TYPE PLUMBING
J 2
(-25 450);
DISPLAY 0.872340 (-25 450);
PAINT GREEN (-25 450);
DISPLAY INVISIBLE (-25 450);
FORCEPROP 1 LAST HDL_TAP TRUE
J 2
(-350 275);
DISPLAY 0.872340 (-350 275);
DISPLAY INVISIBLE (-350 275);
FORCEPROP 1 LAST PATH I19
J 2
(-23 400);
DISPLAY 0.872340 (-23 400);
PAINT GREEN (-23 400);
DISPLAY INVISIBLE (-23 400);
FORCEADD OFFPAGE..2
R 2
(-1050 -125);
FORCEPROP 2 LAST $XR1 89 
J 0
(-1394 -125);
DISPLAY 0.638298 (-1394 -125);
PAINT MONO (-1394 -125);
FORCEPROP 2 LAST $XR0 88 
J 0
(-1304 -125);
DISPLAY 0.638298 (-1304 -125);
PAINT MONO (-1304 -125);
FORCEPROP 2 LAST CDS_LIB standard
J 0
(-1050 -125);
PAINT MONO (-1050 -125);
DISPLAY INVISIBLE (-1050 -125);
FORCEPROP 1 LAST OFFPAGE TRUE
J 2
(-1375 -250);
DISPLAY 0.872340 (-1375 -250);
DISPLAY INVISIBLE (-1375 -250);
FORCEPROP 1 LAST COMMENT_BODY TRUE
J 2
(-1005 -220);
DISPLAY 0.872340 (-1005 -220);
PAINT GREEN (-1005 -220);
DISPLAY INVISIBLE (-1005 -220);
FORCEPROP 2 LAST PATH I2
J 0
(-1000 -50);
DISPLAY 1.021277 (-1000 -50);
DISPLAY INVISIBLE (-1000 -50);
FORCEADD TAP..1
R 2
(-25 450);
FORCEPROP 3 LASTPIN (25 450) SIG_NAME M_D_CPU0_SB_DQ<2>
J 0
(35 460);
DISPLAY 0.659574 (35 460);
PAINT MONO (35 460);
DISPLAY INVISIBLE (35 460);
FORCEPROP 1 LASTPIN (25 450) BN 2
J 2
(37 458);
DISPLAY 0.680851 (37 458);
PAINT GREEN (37 458);
FORCEPROP 2 LAST CDS_LIB standard
J 0
(-25 450);
DISPLAY INVISIBLE (-25 450);
FORCEPROP 1 LAST BODY_TYPE PLUMBING
J 2
(-25 500);
DISPLAY 0.872340 (-25 500);
PAINT GREEN (-25 500);
DISPLAY INVISIBLE (-25 500);
FORCEPROP 1 LAST HDL_TAP TRUE
J 2
(-350 325);
DISPLAY 0.872340 (-350 325);
DISPLAY INVISIBLE (-350 325);
FORCEPROP 1 LAST PATH I20
J 2
(-23 450);
DISPLAY 0.872340 (-23 450);
PAINT GREEN (-23 450);
DISPLAY INVISIBLE (-23 450);
FORCEADD TAP..1
R 2
(-25 500);
FORCEPROP 3 LASTPIN (25 500) SIG_NAME M_D_CPU0_SB_DQ<3>
J 0
(35 510);
DISPLAY 0.659574 (35 510);
PAINT MONO (35 510);
DISPLAY INVISIBLE (35 510);
FORCEPROP 1 LASTPIN (25 500) BN 3
J 2
(37 508);
DISPLAY 0.680851 (37 508);
PAINT GREEN (37 508);
FORCEPROP 2 LAST CDS_LIB standard
J 0
(-25 500);
DISPLAY INVISIBLE (-25 500);
FORCEPROP 1 LAST BODY_TYPE PLUMBING
J 2
(-25 550);
DISPLAY 0.872340 (-25 550);
PAINT GREEN (-25 550);
DISPLAY INVISIBLE (-25 550);
FORCEPROP 1 LAST HDL_TAP TRUE
J 2
(-350 375);
DISPLAY 0.872340 (-350 375);
DISPLAY INVISIBLE (-350 375);
FORCEPROP 1 LAST PATH I21
J 2
(-23 500);
DISPLAY 0.872340 (-23 500);
PAINT GREEN (-23 500);
DISPLAY INVISIBLE (-23 500);
FORCEADD TAP..1
R 2
(-25 550);
FORCEPROP 3 LASTPIN (25 550) SIG_NAME M_D_CPU0_SB_DQ<4>
J 0
(35 560);
DISPLAY 0.659574 (35 560);
PAINT MONO (35 560);
DISPLAY INVISIBLE (35 560);
FORCEPROP 1 LASTPIN (25 550) BN 4
J 2
(37 558);
DISPLAY 0.680851 (37 558);
PAINT GREEN (37 558);
FORCEPROP 2 LAST CDS_LIB standard
J 0
(-25 550);
DISPLAY INVISIBLE (-25 550);
FORCEPROP 1 LAST BODY_TYPE PLUMBING
J 2
(-25 600);
DISPLAY 0.872340 (-25 600);
PAINT GREEN (-25 600);
DISPLAY INVISIBLE (-25 600);
FORCEPROP 1 LAST HDL_TAP TRUE
J 2
(-350 425);
DISPLAY 0.872340 (-350 425);
DISPLAY INVISIBLE (-350 425);
FORCEPROP 1 LAST PATH I22
J 2
(-23 550);
DISPLAY 0.872340 (-23 550);
PAINT GREEN (-23 550);
DISPLAY INVISIBLE (-23 550);
FORCEADD TAP..1
R 2
(-25 600);
FORCEPROP 3 LASTPIN (25 600) SIG_NAME M_D_CPU0_SB_DQ<5>
J 0
(35 610);
DISPLAY 0.659574 (35 610);
PAINT MONO (35 610);
DISPLAY INVISIBLE (35 610);
FORCEPROP 1 LASTPIN (25 600) BN 5
J 2
(37 608);
DISPLAY 0.680851 (37 608);
PAINT GREEN (37 608);
FORCEPROP 2 LAST CDS_LIB standard
J 0
(-25 600);
DISPLAY INVISIBLE (-25 600);
FORCEPROP 1 LAST BODY_TYPE PLUMBING
J 2
(-25 650);
DISPLAY 0.872340 (-25 650);
PAINT GREEN (-25 650);
DISPLAY INVISIBLE (-25 650);
FORCEPROP 1 LAST HDL_TAP TRUE
J 2
(-350 475);
DISPLAY 0.872340 (-350 475);
DISPLAY INVISIBLE (-350 475);
FORCEPROP 1 LAST PATH I23
J 2
(-23 600);
DISPLAY 0.872340 (-23 600);
PAINT GREEN (-23 600);
DISPLAY INVISIBLE (-23 600);
FORCEADD TAP..1
R 2
(-25 650);
FORCEPROP 3 LASTPIN (25 650) SIG_NAME M_D_CPU0_SB_DQ<6>
J 0
(35 660);
DISPLAY 0.659574 (35 660);
PAINT MONO (35 660);
DISPLAY INVISIBLE (35 660);
FORCEPROP 1 LASTPIN (25 650) BN 6
J 2
(37 658);
DISPLAY 0.680851 (37 658);
PAINT GREEN (37 658);
FORCEPROP 2 LAST CDS_LIB standard
J 0
(-25 650);
DISPLAY INVISIBLE (-25 650);
FORCEPROP 1 LAST BODY_TYPE PLUMBING
J 2
(-25 700);
DISPLAY 0.872340 (-25 700);
PAINT GREEN (-25 700);
DISPLAY INVISIBLE (-25 700);
FORCEPROP 1 LAST HDL_TAP TRUE
J 2
(-350 525);
DISPLAY 0.872340 (-350 525);
DISPLAY INVISIBLE (-350 525);
FORCEPROP 1 LAST PATH I24
J 2
(-23 650);
DISPLAY 0.872340 (-23 650);
PAINT GREEN (-23 650);
DISPLAY INVISIBLE (-23 650);
FORCEADD TAP..1
R 2
(-25 700);
FORCEPROP 3 LASTPIN (25 700) SIG_NAME M_D_CPU0_SB_DQ<7>
J 0
(35 710);
DISPLAY 0.659574 (35 710);
PAINT MONO (35 710);
DISPLAY INVISIBLE (35 710);
FORCEPROP 1 LASTPIN (25 700) BN 7
J 2
(37 708);
DISPLAY 0.680851 (37 708);
PAINT GREEN (37 708);
FORCEPROP 2 LAST CDS_LIB standard
J 0
(-25 700);
DISPLAY INVISIBLE (-25 700);
FORCEPROP 1 LAST BODY_TYPE PLUMBING
J 2
(-25 750);
DISPLAY 0.872340 (-25 750);
PAINT GREEN (-25 750);
DISPLAY INVISIBLE (-25 750);
FORCEPROP 1 LAST HDL_TAP TRUE
J 2
(-350 575);
DISPLAY 0.872340 (-350 575);
DISPLAY INVISIBLE (-350 575);
FORCEPROP 1 LAST PATH I25
J 2
(-23 700);
DISPLAY 0.872340 (-23 700);
PAINT GREEN (-23 700);
DISPLAY INVISIBLE (-23 700);
FORCEADD TAP..1
R 2
(-25 750);
FORCEPROP 3 LASTPIN (25 750) SIG_NAME M_D_CPU0_SB_DQ<8>
J 0
(35 760);
DISPLAY 0.659574 (35 760);
PAINT MONO (35 760);
DISPLAY INVISIBLE (35 760);
FORCEPROP 1 LASTPIN (25 750) BN 8
J 2
(37 758);
DISPLAY 0.680851 (37 758);
PAINT GREEN (37 758);
FORCEPROP 2 LAST CDS_LIB standard
J 0
(-25 750);
DISPLAY INVISIBLE (-25 750);
FORCEPROP 1 LAST BODY_TYPE PLUMBING
J 2
(-25 800);
DISPLAY 0.872340 (-25 800);
PAINT GREEN (-25 800);
DISPLAY INVISIBLE (-25 800);
FORCEPROP 1 LAST HDL_TAP TRUE
J 2
(-350 625);
DISPLAY 0.872340 (-350 625);
DISPLAY INVISIBLE (-350 625);
FORCEPROP 1 LAST PATH I26
J 2
(-23 750);
DISPLAY 0.872340 (-23 750);
PAINT GREEN (-23 750);
DISPLAY INVISIBLE (-23 750);
FORCEADD TAP..1
R 2
(-25 800);
FORCEPROP 3 LASTPIN (25 800) SIG_NAME M_D_CPU0_SB_DQ<9>
J 0
(35 810);
DISPLAY 0.659574 (35 810);
PAINT MONO (35 810);
DISPLAY INVISIBLE (35 810);
FORCEPROP 1 LASTPIN (25 800) BN 9
J 2
(37 808);
DISPLAY 0.680851 (37 808);
PAINT GREEN (37 808);
FORCEPROP 2 LAST CDS_LIB standard
J 0
(-25 800);
DISPLAY INVISIBLE (-25 800);
FORCEPROP 1 LAST BODY_TYPE PLUMBING
J 2
(-25 850);
DISPLAY 0.872340 (-25 850);
PAINT GREEN (-25 850);
DISPLAY INVISIBLE (-25 850);
FORCEPROP 1 LAST HDL_TAP TRUE
J 2
(-350 675);
DISPLAY 0.872340 (-350 675);
DISPLAY INVISIBLE (-350 675);
FORCEPROP 1 LAST PATH I27
J 2
(-23 800);
DISPLAY 0.872340 (-23 800);
PAINT GREEN (-23 800);
DISPLAY INVISIBLE (-23 800);
FORCEADD TAP..1
R 2
(-25 850);
FORCEPROP 3 LASTPIN (25 850) SIG_NAME M_D_CPU0_SB_DQ<10>
J 0
(35 860);
DISPLAY 0.659574 (35 860);
PAINT MONO (35 860);
DISPLAY INVISIBLE (35 860);
FORCEPROP 1 LASTPIN (25 850) BN 10
J 2
(37 858);
DISPLAY 0.680851 (37 858);
PAINT GREEN (37 858);
FORCEPROP 2 LAST CDS_LIB standard
J 0
(-25 850);
DISPLAY INVISIBLE (-25 850);
FORCEPROP 1 LAST BODY_TYPE PLUMBING
J 2
(-25 900);
DISPLAY 0.872340 (-25 900);
PAINT GREEN (-25 900);
DISPLAY INVISIBLE (-25 900);
FORCEPROP 1 LAST HDL_TAP TRUE
J 2
(-350 725);
DISPLAY 0.872340 (-350 725);
DISPLAY INVISIBLE (-350 725);
FORCEPROP 1 LAST PATH I28
J 2
(-23 850);
DISPLAY 0.872340 (-23 850);
PAINT GREEN (-23 850);
DISPLAY INVISIBLE (-23 850);
FORCEADD TAP..1
R 2
(-25 900);
FORCEPROP 3 LASTPIN (25 900) SIG_NAME M_D_CPU0_SB_DQ<11>
J 0
(35 910);
DISPLAY 0.659574 (35 910);
PAINT MONO (35 910);
DISPLAY INVISIBLE (35 910);
FORCEPROP 1 LASTPIN (25 900) BN 11
J 2
(37 908);
DISPLAY 0.680851 (37 908);
PAINT GREEN (37 908);
FORCEPROP 2 LAST CDS_LIB standard
J 0
(-25 900);
DISPLAY INVISIBLE (-25 900);
FORCEPROP 1 LAST BODY_TYPE PLUMBING
J 2
(-25 950);
DISPLAY 0.872340 (-25 950);
PAINT GREEN (-25 950);
DISPLAY INVISIBLE (-25 950);
FORCEPROP 1 LAST HDL_TAP TRUE
J 2
(-350 775);
DISPLAY 0.872340 (-350 775);
DISPLAY INVISIBLE (-350 775);
FORCEPROP 1 LAST PATH I29
J 2
(-23 900);
DISPLAY 0.872340 (-23 900);
PAINT GREEN (-23 900);
DISPLAY INVISIBLE (-23 900);
FORCEADD TAP..1
R 2
(-25 -300);
FORCEPROP 3 LASTPIN (25 -300) SIG_NAME M_D_CPU0_CLK_DN<0>
J 0
(35 -290);
DISPLAY 0.659574 (35 -290);
PAINT MONO (35 -290);
DISPLAY INVISIBLE (35 -290);
FORCEPROP 1 LASTPIN (25 -300) BN 0
J 2
(37 -292);
DISPLAY 0.680851 (37 -292);
PAINT GREEN (37 -292);
FORCEPROP 2 LAST CDS_LIB standard
J 0
(-25 -300);
DISPLAY INVISIBLE (-25 -300);
FORCEPROP 1 LAST BODY_TYPE PLUMBING
J 2
(-25 -250);
DISPLAY 0.872340 (-25 -250);
PAINT GREEN (-25 -250);
DISPLAY INVISIBLE (-25 -250);
FORCEPROP 1 LAST HDL_TAP TRUE
J 2
(-350 -425);
DISPLAY 0.872340 (-350 -425);
DISPLAY INVISIBLE (-350 -425);
FORCEPROP 1 LAST PATH I3
J 2
(-23 -300);
DISPLAY 0.872340 (-23 -300);
PAINT GREEN (-23 -300);
DISPLAY INVISIBLE (-23 -300);
FORCEADD TAP..1
R 2
(-25 950);
FORCEPROP 3 LASTPIN (25 950) SIG_NAME M_D_CPU0_SB_DQ<12>
J 0
(35 960);
DISPLAY 0.659574 (35 960);
PAINT MONO (35 960);
DISPLAY INVISIBLE (35 960);
FORCEPROP 1 LASTPIN (25 950) BN 12
J 2
(37 958);
DISPLAY 0.680851 (37 958);
PAINT GREEN (37 958);
FORCEPROP 2 LAST CDS_LIB standard
J 0
(-25 950);
DISPLAY INVISIBLE (-25 950);
FORCEPROP 1 LAST BODY_TYPE PLUMBING
J 2
(-25 1000);
DISPLAY 0.872340 (-25 1000);
PAINT GREEN (-25 1000);
DISPLAY INVISIBLE (-25 1000);
FORCEPROP 1 LAST HDL_TAP TRUE
J 2
(-350 825);
DISPLAY 0.872340 (-350 825);
DISPLAY INVISIBLE (-350 825);
FORCEPROP 1 LAST PATH I30
J 2
(-23 950);
DISPLAY 0.872340 (-23 950);
PAINT GREEN (-23 950);
DISPLAY INVISIBLE (-23 950);
FORCEADD TAP..1
R 2
(-25 1000);
FORCEPROP 3 LASTPIN (25 1000) SIG_NAME M_D_CPU0_SB_DQ<13>
J 0
(35 1010);
DISPLAY 0.659574 (35 1010);
PAINT MONO (35 1010);
DISPLAY INVISIBLE (35 1010);
FORCEPROP 1 LASTPIN (25 1000) BN 13
J 2
(37 1008);
DISPLAY 0.680851 (37 1008);
PAINT GREEN (37 1008);
FORCEPROP 2 LAST CDS_LIB standard
J 0
(-25 1000);
DISPLAY INVISIBLE (-25 1000);
FORCEPROP 1 LAST BODY_TYPE PLUMBING
J 2
(-25 1050);
DISPLAY 0.872340 (-25 1050);
PAINT GREEN (-25 1050);
DISPLAY INVISIBLE (-25 1050);
FORCEPROP 1 LAST HDL_TAP TRUE
J 2
(-350 875);
DISPLAY 0.872340 (-350 875);
DISPLAY INVISIBLE (-350 875);
FORCEPROP 1 LAST PATH I31
J 2
(-23 1000);
DISPLAY 0.872340 (-23 1000);
PAINT GREEN (-23 1000);
DISPLAY INVISIBLE (-23 1000);
FORCEADD TAP..1
R 2
(-25 1050);
FORCEPROP 3 LASTPIN (25 1050) SIG_NAME M_D_CPU0_SB_DQ<14>
J 0
(35 1060);
DISPLAY 0.659574 (35 1060);
PAINT MONO (35 1060);
DISPLAY INVISIBLE (35 1060);
FORCEPROP 1 LASTPIN (25 1050) BN 14
J 2
(37 1058);
DISPLAY 0.680851 (37 1058);
PAINT GREEN (37 1058);
FORCEPROP 2 LAST CDS_LIB standard
J 0
(-25 1050);
DISPLAY INVISIBLE (-25 1050);
FORCEPROP 1 LAST BODY_TYPE PLUMBING
J 2
(-25 1100);
DISPLAY 0.872340 (-25 1100);
PAINT GREEN (-25 1100);
DISPLAY INVISIBLE (-25 1100);
FORCEPROP 1 LAST HDL_TAP TRUE
J 2
(-350 925);
DISPLAY 0.872340 (-350 925);
DISPLAY INVISIBLE (-350 925);
FORCEPROP 1 LAST PATH I32
J 2
(-23 1050);
DISPLAY 0.872340 (-23 1050);
PAINT GREEN (-23 1050);
DISPLAY INVISIBLE (-23 1050);
FORCEADD TAP..1
R 2
(-25 1100);
FORCEPROP 3 LASTPIN (25 1100) SIG_NAME M_D_CPU0_SB_DQ<15>
J 0
(35 1110);
DISPLAY 0.659574 (35 1110);
PAINT MONO (35 1110);
DISPLAY INVISIBLE (35 1110);
FORCEPROP 1 LASTPIN (25 1100) BN 15
J 2
(37 1108);
DISPLAY 0.680851 (37 1108);
PAINT GREEN (37 1108);
FORCEPROP 2 LAST CDS_LIB standard
J 0
(-25 1100);
DISPLAY INVISIBLE (-25 1100);
FORCEPROP 1 LAST BODY_TYPE PLUMBING
J 2
(-25 1150);
DISPLAY 0.872340 (-25 1150);
PAINT GREEN (-25 1150);
DISPLAY INVISIBLE (-25 1150);
FORCEPROP 1 LAST HDL_TAP TRUE
J 2
(-350 975);
DISPLAY 0.872340 (-350 975);
DISPLAY INVISIBLE (-350 975);
FORCEPROP 1 LAST PATH I33
J 2
(-23 1100);
DISPLAY 0.872340 (-23 1100);
PAINT GREEN (-23 1100);
DISPLAY INVISIBLE (-23 1100);
FORCEADD TAP..1
R 2
(-25 1150);
FORCEPROP 3 LASTPIN (25 1150) SIG_NAME M_D_CPU0_SB_DQ<16>
J 0
(35 1160);
DISPLAY 0.659574 (35 1160);
PAINT MONO (35 1160);
DISPLAY INVISIBLE (35 1160);
FORCEPROP 1 LASTPIN (25 1150) BN 16
J 2
(37 1158);
DISPLAY 0.680851 (37 1158);
PAINT GREEN (37 1158);
FORCEPROP 2 LAST CDS_LIB standard
J 0
(-25 1150);
DISPLAY INVISIBLE (-25 1150);
FORCEPROP 1 LAST BODY_TYPE PLUMBING
J 2
(-25 1200);
DISPLAY 0.872340 (-25 1200);
PAINT GREEN (-25 1200);
DISPLAY INVISIBLE (-25 1200);
FORCEPROP 1 LAST HDL_TAP TRUE
J 2
(-350 1025);
DISPLAY 0.872340 (-350 1025);
DISPLAY INVISIBLE (-350 1025);
FORCEPROP 1 LAST PATH I34
J 2
(-23 1150);
DISPLAY 0.872340 (-23 1150);
PAINT GREEN (-23 1150);
DISPLAY INVISIBLE (-23 1150);
FORCEADD TAP..1
R 2
(-25 1200);
FORCEPROP 3 LASTPIN (25 1200) SIG_NAME M_D_CPU0_SB_DQ<17>
J 0
(35 1210);
DISPLAY 0.659574 (35 1210);
PAINT MONO (35 1210);
DISPLAY INVISIBLE (35 1210);
FORCEPROP 1 LASTPIN (25 1200) BN 17
J 2
(37 1208);
DISPLAY 0.680851 (37 1208);
PAINT GREEN (37 1208);
FORCEPROP 2 LAST CDS_LIB standard
J 0
(-25 1200);
DISPLAY INVISIBLE (-25 1200);
FORCEPROP 1 LAST BODY_TYPE PLUMBING
J 2
(-25 1250);
DISPLAY 0.872340 (-25 1250);
PAINT GREEN (-25 1250);
DISPLAY INVISIBLE (-25 1250);
FORCEPROP 1 LAST HDL_TAP TRUE
J 2
(-350 1075);
DISPLAY 0.872340 (-350 1075);
DISPLAY INVISIBLE (-350 1075);
FORCEPROP 1 LAST PATH I35
J 2
(-23 1200);
DISPLAY 0.872340 (-23 1200);
PAINT GREEN (-23 1200);
DISPLAY INVISIBLE (-23 1200);
FORCEADD TAP..1
R 2
(-25 1250);
FORCEPROP 3 LASTPIN (25 1250) SIG_NAME M_D_CPU0_SB_DQ<18>
J 0
(35 1260);
DISPLAY 0.659574 (35 1260);
PAINT MONO (35 1260);
DISPLAY INVISIBLE (35 1260);
FORCEPROP 1 LASTPIN (25 1250) BN 18
J 2
(37 1258);
DISPLAY 0.680851 (37 1258);
PAINT GREEN (37 1258);
FORCEPROP 2 LAST CDS_LIB standard
J 0
(-25 1250);
DISPLAY INVISIBLE (-25 1250);
FORCEPROP 1 LAST BODY_TYPE PLUMBING
J 2
(-25 1300);
DISPLAY 0.872340 (-25 1300);
PAINT GREEN (-25 1300);
DISPLAY INVISIBLE (-25 1300);
FORCEPROP 1 LAST HDL_TAP TRUE
J 2
(-350 1125);
DISPLAY 0.872340 (-350 1125);
DISPLAY INVISIBLE (-350 1125);
FORCEPROP 1 LAST PATH I36
J 2
(-23 1250);
DISPLAY 0.872340 (-23 1250);
PAINT GREEN (-23 1250);
DISPLAY INVISIBLE (-23 1250);
FORCEADD TAP..1
R 2
(-25 1300);
FORCEPROP 3 LASTPIN (25 1300) SIG_NAME M_D_CPU0_SB_DQ<19>
J 0
(35 1310);
DISPLAY 0.659574 (35 1310);
PAINT MONO (35 1310);
DISPLAY INVISIBLE (35 1310);
FORCEPROP 1 LASTPIN (25 1300) BN 19
J 2
(37 1308);
DISPLAY 0.680851 (37 1308);
PAINT GREEN (37 1308);
FORCEPROP 2 LAST CDS_LIB standard
J 0
(-25 1300);
DISPLAY INVISIBLE (-25 1300);
FORCEPROP 1 LAST BODY_TYPE PLUMBING
J 2
(-25 1350);
DISPLAY 0.872340 (-25 1350);
PAINT GREEN (-25 1350);
DISPLAY INVISIBLE (-25 1350);
FORCEPROP 1 LAST HDL_TAP TRUE
J 2
(-350 1175);
DISPLAY 0.872340 (-350 1175);
DISPLAY INVISIBLE (-350 1175);
FORCEPROP 1 LAST PATH I37
J 2
(-23 1300);
DISPLAY 0.872340 (-23 1300);
PAINT GREEN (-23 1300);
DISPLAY INVISIBLE (-23 1300);
FORCEADD TAP..1
R 2
(-25 1350);
FORCEPROP 3 LASTPIN (25 1350) SIG_NAME M_D_CPU0_SB_DQ<20>
J 0
(35 1360);
DISPLAY 0.659574 (35 1360);
PAINT MONO (35 1360);
DISPLAY INVISIBLE (35 1360);
FORCEPROP 1 LASTPIN (25 1350) BN 20
J 2
(37 1358);
DISPLAY 0.680851 (37 1358);
PAINT GREEN (37 1358);
FORCEPROP 2 LAST CDS_LIB standard
J 0
(-25 1350);
DISPLAY INVISIBLE (-25 1350);
FORCEPROP 1 LAST BODY_TYPE PLUMBING
J 2
(-25 1400);
DISPLAY 0.872340 (-25 1400);
PAINT GREEN (-25 1400);
DISPLAY INVISIBLE (-25 1400);
FORCEPROP 1 LAST HDL_TAP TRUE
J 2
(-350 1225);
DISPLAY 0.872340 (-350 1225);
DISPLAY INVISIBLE (-350 1225);
FORCEPROP 1 LAST PATH I38
J 2
(-23 1350);
DISPLAY 0.872340 (-23 1350);
PAINT GREEN (-23 1350);
DISPLAY INVISIBLE (-23 1350);
FORCEADD TAP..1
R 2
(-25 1400);
FORCEPROP 3 LASTPIN (25 1400) SIG_NAME M_D_CPU0_SB_DQ<21>
J 0
(35 1410);
DISPLAY 0.659574 (35 1410);
PAINT MONO (35 1410);
DISPLAY INVISIBLE (35 1410);
FORCEPROP 1 LASTPIN (25 1400) BN 21
J 2
(37 1408);
DISPLAY 0.680851 (37 1408);
PAINT GREEN (37 1408);
FORCEPROP 2 LAST CDS_LIB standard
J 0
(-25 1400);
DISPLAY INVISIBLE (-25 1400);
FORCEPROP 1 LAST BODY_TYPE PLUMBING
J 2
(-25 1450);
DISPLAY 0.872340 (-25 1450);
PAINT GREEN (-25 1450);
DISPLAY INVISIBLE (-25 1450);
FORCEPROP 1 LAST HDL_TAP TRUE
J 2
(-350 1275);
DISPLAY 0.872340 (-350 1275);
DISPLAY INVISIBLE (-350 1275);
FORCEPROP 1 LAST PATH I39
J 2
(-23 1400);
DISPLAY 0.872340 (-23 1400);
PAINT GREEN (-23 1400);
DISPLAY INVISIBLE (-23 1400);
FORCEADD TAP..1
R 2
(-25 -50);
FORCEPROP 3 LASTPIN (25 -50) SIG_NAME M_D_CPU0_SB_CB<0>
J 0
(35 -40);
DISPLAY 0.659574 (35 -40);
PAINT MONO (35 -40);
DISPLAY INVISIBLE (35 -40);
FORCEPROP 1 LASTPIN (25 -50) BN 0
J 2
(37 -42);
DISPLAY 0.680851 (37 -42);
PAINT GREEN (37 -42);
FORCEPROP 2 LAST CDS_LIB standard
J 0
(-25 -50);
DISPLAY INVISIBLE (-25 -50);
FORCEPROP 1 LAST BODY_TYPE PLUMBING
J 2
(-25 0);
DISPLAY 0.872340 (-25 0);
PAINT GREEN (-25 0);
DISPLAY INVISIBLE (-25 0);
FORCEPROP 1 LAST HDL_TAP TRUE
J 2
(-350 -175);
DISPLAY 0.872340 (-350 -175);
DISPLAY INVISIBLE (-350 -175);
FORCEPROP 1 LAST PATH I4
J 2
(-23 -50);
DISPLAY 0.872340 (-23 -50);
PAINT GREEN (-23 -50);
DISPLAY INVISIBLE (-23 -50);
FORCEADD TAP..1
R 2
(-25 1450);
FORCEPROP 3 LASTPIN (25 1450) SIG_NAME M_D_CPU0_SB_DQ<22>
J 0
(35 1460);
DISPLAY 0.659574 (35 1460);
PAINT MONO (35 1460);
DISPLAY INVISIBLE (35 1460);
FORCEPROP 1 LASTPIN (25 1450) BN 22
J 2
(37 1458);
DISPLAY 0.680851 (37 1458);
PAINT GREEN (37 1458);
FORCEPROP 2 LAST CDS_LIB standard
J 0
(-25 1450);
DISPLAY INVISIBLE (-25 1450);
FORCEPROP 1 LAST BODY_TYPE PLUMBING
J 2
(-25 1500);
DISPLAY 0.872340 (-25 1500);
PAINT GREEN (-25 1500);
DISPLAY INVISIBLE (-25 1500);
FORCEPROP 1 LAST HDL_TAP TRUE
J 2
(-350 1325);
DISPLAY 0.872340 (-350 1325);
DISPLAY INVISIBLE (-350 1325);
FORCEPROP 1 LAST PATH I40
J 2
(-23 1450);
DISPLAY 0.872340 (-23 1450);
PAINT GREEN (-23 1450);
DISPLAY INVISIBLE (-23 1450);
FORCEADD TAP..1
R 2
(-25 1500);
FORCEPROP 3 LASTPIN (25 1500) SIG_NAME M_D_CPU0_SB_DQ<23>
J 0
(35 1510);
DISPLAY 0.659574 (35 1510);
PAINT MONO (35 1510);
DISPLAY INVISIBLE (35 1510);
FORCEPROP 1 LASTPIN (25 1500) BN 23
J 2
(37 1508);
DISPLAY 0.680851 (37 1508);
PAINT GREEN (37 1508);
FORCEPROP 2 LAST CDS_LIB standard
J 0
(-25 1500);
DISPLAY INVISIBLE (-25 1500);
FORCEPROP 1 LAST BODY_TYPE PLUMBING
J 2
(-25 1550);
DISPLAY 0.872340 (-25 1550);
PAINT GREEN (-25 1550);
DISPLAY INVISIBLE (-25 1550);
FORCEPROP 1 LAST HDL_TAP TRUE
J 2
(-350 1375);
DISPLAY 0.872340 (-350 1375);
DISPLAY INVISIBLE (-350 1375);
FORCEPROP 1 LAST PATH I41
J 2
(-23 1500);
DISPLAY 0.872340 (-23 1500);
PAINT GREEN (-23 1500);
DISPLAY INVISIBLE (-23 1500);
FORCEADD TAP..1
R 2
(-25 1550);
FORCEPROP 3 LASTPIN (25 1550) SIG_NAME M_D_CPU0_SB_DQ<24>
J 0
(35 1560);
DISPLAY 0.659574 (35 1560);
PAINT MONO (35 1560);
DISPLAY INVISIBLE (35 1560);
FORCEPROP 1 LASTPIN (25 1550) BN 24
J 2
(37 1558);
DISPLAY 0.680851 (37 1558);
PAINT GREEN (37 1558);
FORCEPROP 2 LAST CDS_LIB standard
J 0
(-25 1550);
DISPLAY INVISIBLE (-25 1550);
FORCEPROP 1 LAST BODY_TYPE PLUMBING
J 2
(-25 1600);
DISPLAY 0.872340 (-25 1600);
PAINT GREEN (-25 1600);
DISPLAY INVISIBLE (-25 1600);
FORCEPROP 1 LAST HDL_TAP TRUE
J 2
(-350 1425);
DISPLAY 0.872340 (-350 1425);
DISPLAY INVISIBLE (-350 1425);
FORCEPROP 1 LAST PATH I42
J 2
(-23 1550);
DISPLAY 0.872340 (-23 1550);
PAINT GREEN (-23 1550);
DISPLAY INVISIBLE (-23 1550);
FORCEADD TAP..1
R 2
(-25 1600);
FORCEPROP 3 LASTPIN (25 1600) SIG_NAME M_D_CPU0_SB_DQ<25>
J 0
(35 1610);
DISPLAY 0.659574 (35 1610);
PAINT MONO (35 1610);
DISPLAY INVISIBLE (35 1610);
FORCEPROP 1 LASTPIN (25 1600) BN 25
J 2
(37 1608);
DISPLAY 0.680851 (37 1608);
PAINT GREEN (37 1608);
FORCEPROP 2 LAST CDS_LIB standard
J 0
(-25 1600);
DISPLAY INVISIBLE (-25 1600);
FORCEPROP 1 LAST BODY_TYPE PLUMBING
J 2
(-25 1650);
DISPLAY 0.872340 (-25 1650);
PAINT GREEN (-25 1650);
DISPLAY INVISIBLE (-25 1650);
FORCEPROP 1 LAST HDL_TAP TRUE
J 2
(-350 1475);
DISPLAY 0.872340 (-350 1475);
DISPLAY INVISIBLE (-350 1475);
FORCEPROP 1 LAST PATH I43
J 2
(-23 1600);
DISPLAY 0.872340 (-23 1600);
PAINT GREEN (-23 1600);
DISPLAY INVISIBLE (-23 1600);
FORCEADD TAP..1
R 2
(-25 1650);
FORCEPROP 3 LASTPIN (25 1650) SIG_NAME M_D_CPU0_SB_DQ<26>
J 0
(35 1660);
DISPLAY 0.659574 (35 1660);
PAINT MONO (35 1660);
DISPLAY INVISIBLE (35 1660);
FORCEPROP 1 LASTPIN (25 1650) BN 26
J 2
(37 1658);
DISPLAY 0.680851 (37 1658);
PAINT GREEN (37 1658);
FORCEPROP 2 LAST CDS_LIB standard
J 0
(-25 1650);
DISPLAY INVISIBLE (-25 1650);
FORCEPROP 1 LAST BODY_TYPE PLUMBING
J 2
(-25 1700);
DISPLAY 0.872340 (-25 1700);
PAINT GREEN (-25 1700);
DISPLAY INVISIBLE (-25 1700);
FORCEPROP 1 LAST HDL_TAP TRUE
J 2
(-350 1525);
DISPLAY 0.872340 (-350 1525);
DISPLAY INVISIBLE (-350 1525);
FORCEPROP 1 LAST PATH I44
J 2
(-23 1650);
DISPLAY 0.872340 (-23 1650);
PAINT GREEN (-23 1650);
DISPLAY INVISIBLE (-23 1650);
FORCEADD TAP..1
R 2
(-25 1700);
FORCEPROP 3 LASTPIN (25 1700) SIG_NAME M_D_CPU0_SB_DQ<27>
J 0
(35 1710);
DISPLAY 0.659574 (35 1710);
PAINT MONO (35 1710);
DISPLAY INVISIBLE (35 1710);
FORCEPROP 1 LASTPIN (25 1700) BN 27
J 2
(37 1708);
DISPLAY 0.680851 (37 1708);
PAINT GREEN (37 1708);
FORCEPROP 2 LAST CDS_LIB standard
J 0
(-25 1700);
DISPLAY INVISIBLE (-25 1700);
FORCEPROP 1 LAST BODY_TYPE PLUMBING
J 2
(-25 1750);
DISPLAY 0.872340 (-25 1750);
PAINT GREEN (-25 1750);
DISPLAY INVISIBLE (-25 1750);
FORCEPROP 1 LAST HDL_TAP TRUE
J 2
(-350 1575);
DISPLAY 0.872340 (-350 1575);
DISPLAY INVISIBLE (-350 1575);
FORCEPROP 1 LAST PATH I45
J 2
(-23 1700);
DISPLAY 0.872340 (-23 1700);
PAINT GREEN (-23 1700);
DISPLAY INVISIBLE (-23 1700);
FORCEADD TAP..1
R 2
(-25 1750);
FORCEPROP 3 LASTPIN (25 1750) SIG_NAME M_D_CPU0_SB_DQ<28>
J 0
(35 1760);
DISPLAY 0.659574 (35 1760);
PAINT MONO (35 1760);
DISPLAY INVISIBLE (35 1760);
FORCEPROP 1 LASTPIN (25 1750) BN 28
J 2
(37 1758);
DISPLAY 0.680851 (37 1758);
PAINT GREEN (37 1758);
FORCEPROP 2 LAST CDS_LIB standard
J 0
(-25 1750);
DISPLAY INVISIBLE (-25 1750);
FORCEPROP 1 LAST BODY_TYPE PLUMBING
J 2
(-25 1800);
DISPLAY 0.872340 (-25 1800);
PAINT GREEN (-25 1800);
DISPLAY INVISIBLE (-25 1800);
FORCEPROP 1 LAST HDL_TAP TRUE
J 2
(-350 1625);
DISPLAY 0.872340 (-350 1625);
DISPLAY INVISIBLE (-350 1625);
FORCEPROP 1 LAST PATH I46
J 2
(-23 1750);
DISPLAY 0.872340 (-23 1750);
PAINT GREEN (-23 1750);
DISPLAY INVISIBLE (-23 1750);
FORCEADD TAP..1
R 2
(-25 1800);
FORCEPROP 3 LASTPIN (25 1800) SIG_NAME M_D_CPU0_SB_DQ<29>
J 0
(35 1810);
DISPLAY 0.659574 (35 1810);
PAINT MONO (35 1810);
DISPLAY INVISIBLE (35 1810);
FORCEPROP 1 LASTPIN (25 1800) BN 29
J 2
(37 1808);
DISPLAY 0.680851 (37 1808);
PAINT GREEN (37 1808);
FORCEPROP 2 LAST CDS_LIB standard
J 0
(-25 1800);
DISPLAY INVISIBLE (-25 1800);
FORCEPROP 1 LAST BODY_TYPE PLUMBING
J 2
(-25 1850);
DISPLAY 0.872340 (-25 1850);
PAINT GREEN (-25 1850);
DISPLAY INVISIBLE (-25 1850);
FORCEPROP 1 LAST HDL_TAP TRUE
J 2
(-350 1675);
DISPLAY 0.872340 (-350 1675);
DISPLAY INVISIBLE (-350 1675);
FORCEPROP 1 LAST PATH I47
J 2
(-23 1800);
DISPLAY 0.872340 (-23 1800);
PAINT GREEN (-23 1800);
DISPLAY INVISIBLE (-23 1800);
FORCEADD TAP..1
R 2
(-25 1900);
FORCEPROP 3 LASTPIN (25 1900) SIG_NAME M_D_CPU0_SB_DQ<31>
J 0
(35 1910);
DISPLAY 0.659574 (35 1910);
PAINT MONO (35 1910);
DISPLAY INVISIBLE (35 1910);
FORCEPROP 1 LASTPIN (25 1900) BN 31
J 2
(37 1908);
DISPLAY 0.680851 (37 1908);
PAINT GREEN (37 1908);
FORCEPROP 2 LAST CDS_LIB standard
J 0
(-25 1900);
DISPLAY INVISIBLE (-25 1900);
FORCEPROP 1 LAST BODY_TYPE PLUMBING
J 2
(-25 1950);
DISPLAY 0.872340 (-25 1950);
PAINT GREEN (-25 1950);
DISPLAY INVISIBLE (-25 1950);
FORCEPROP 1 LAST HDL_TAP TRUE
J 2
(-350 1775);
DISPLAY 0.872340 (-350 1775);
DISPLAY INVISIBLE (-350 1775);
FORCEPROP 1 LAST PATH I48
J 2
(-23 1900);
DISPLAY 0.872340 (-23 1900);
PAINT GREEN (-23 1900);
DISPLAY INVISIBLE (-23 1900);
FORCEADD TAP..1
R 2
(-25 1850);
FORCEPROP 3 LASTPIN (25 1850) SIG_NAME M_D_CPU0_SB_DQ<30>
J 0
(35 1860);
DISPLAY 0.659574 (35 1860);
PAINT MONO (35 1860);
DISPLAY INVISIBLE (35 1860);
FORCEPROP 1 LASTPIN (25 1850) BN 30
J 2
(37 1858);
DISPLAY 0.680851 (37 1858);
PAINT GREEN (37 1858);
FORCEPROP 2 LAST CDS_LIB standard
J 0
(-25 1850);
DISPLAY INVISIBLE (-25 1850);
FORCEPROP 1 LAST BODY_TYPE PLUMBING
J 2
(-25 1900);
DISPLAY 0.872340 (-25 1900);
PAINT GREEN (-25 1900);
DISPLAY INVISIBLE (-25 1900);
FORCEPROP 1 LAST HDL_TAP TRUE
J 2
(-350 1725);
DISPLAY 0.872340 (-350 1725);
DISPLAY INVISIBLE (-350 1725);
FORCEPROP 1 LAST PATH I49
J 2
(-23 1850);
DISPLAY 0.872340 (-23 1850);
PAINT GREEN (-23 1850);
DISPLAY INVISIBLE (-23 1850);
FORCEADD TAP..1
R 2
(-25 -200);
FORCEPROP 3 LASTPIN (25 -200) SIG_NAME M_D_CPU0_CLK_DP<0>
J 0
(35 -190);
DISPLAY 0.659574 (35 -190);
PAINT MONO (35 -190);
DISPLAY INVISIBLE (35 -190);
FORCEPROP 1 LASTPIN (25 -200) BN 0
J 2
(37 -192);
DISPLAY 0.680851 (37 -192);
PAINT GREEN (37 -192);
FORCEPROP 2 LAST CDS_LIB standard
J 0
(-25 -200);
DISPLAY INVISIBLE (-25 -200);
FORCEPROP 1 LAST BODY_TYPE PLUMBING
J 2
(-25 -150);
DISPLAY 0.872340 (-25 -150);
PAINT GREEN (-25 -150);
DISPLAY INVISIBLE (-25 -150);
FORCEPROP 1 LAST HDL_TAP TRUE
J 2
(-350 -325);
DISPLAY 0.872340 (-350 -325);
DISPLAY INVISIBLE (-350 -325);
FORCEPROP 1 LAST PATH I5
J 2
(-23 -200);
DISPLAY 0.872340 (-23 -200);
PAINT GREEN (-23 -200);
DISPLAY INVISIBLE (-23 -200);
FORCEADD TAP..1
R 2
(-25 1950);
FORCEPROP 3 LASTPIN (25 1950) SIG_NAME M_D_CPU0_SA_CB<0>
J 0
(35 1960);
DISPLAY 0.659574 (35 1960);
PAINT MONO (35 1960);
DISPLAY INVISIBLE (35 1960);
FORCEPROP 1 LASTPIN (25 1950) BN 0
J 2
(37 1958);
DISPLAY 0.680851 (37 1958);
PAINT GREEN (37 1958);
FORCEPROP 2 LAST CDS_LIB standard
J 0
(-25 1950);
DISPLAY INVISIBLE (-25 1950);
FORCEPROP 1 LAST BODY_TYPE PLUMBING
J 2
(-25 2000);
DISPLAY 0.872340 (-25 2000);
PAINT GREEN (-25 2000);
DISPLAY INVISIBLE (-25 2000);
FORCEPROP 1 LAST HDL_TAP TRUE
J 2
(-350 1825);
DISPLAY 0.872340 (-350 1825);
DISPLAY INVISIBLE (-350 1825);
FORCEPROP 1 LAST PATH I50
J 2
(-23 1950);
DISPLAY 0.872340 (-23 1950);
PAINT GREEN (-23 1950);
DISPLAY INVISIBLE (-23 1950);
FORCEADD TAP..1
R 2
(-25 2000);
FORCEPROP 3 LASTPIN (25 2000) SIG_NAME M_D_CPU0_SA_CB<1>
J 0
(35 2010);
DISPLAY 0.659574 (35 2010);
PAINT MONO (35 2010);
DISPLAY INVISIBLE (35 2010);
FORCEPROP 1 LASTPIN (25 2000) BN 1
J 2
(37 2008);
DISPLAY 0.680851 (37 2008);
PAINT GREEN (37 2008);
FORCEPROP 2 LAST CDS_LIB standard
J 0
(-25 2000);
DISPLAY INVISIBLE (-25 2000);
FORCEPROP 1 LAST BODY_TYPE PLUMBING
J 2
(-25 2050);
DISPLAY 0.872340 (-25 2050);
PAINT GREEN (-25 2050);
DISPLAY INVISIBLE (-25 2050);
FORCEPROP 1 LAST HDL_TAP TRUE
J 2
(-350 1875);
DISPLAY 0.872340 (-350 1875);
DISPLAY INVISIBLE (-350 1875);
FORCEPROP 1 LAST PATH I51
J 2
(-23 2000);
DISPLAY 0.872340 (-23 2000);
PAINT GREEN (-23 2000);
DISPLAY INVISIBLE (-23 2000);
FORCEADD TAP..1
R 2
(-25 2050);
FORCEPROP 3 LASTPIN (25 2050) SIG_NAME M_D_CPU0_SA_CB<2>
J 0
(35 2060);
DISPLAY 0.659574 (35 2060);
PAINT MONO (35 2060);
DISPLAY INVISIBLE (35 2060);
FORCEPROP 1 LASTPIN (25 2050) BN 2
J 2
(37 2058);
DISPLAY 0.680851 (37 2058);
PAINT GREEN (37 2058);
FORCEPROP 2 LAST CDS_LIB standard
J 0
(-25 2050);
DISPLAY INVISIBLE (-25 2050);
FORCEPROP 1 LAST BODY_TYPE PLUMBING
J 2
(-25 2100);
DISPLAY 0.872340 (-25 2100);
PAINT GREEN (-25 2100);
DISPLAY INVISIBLE (-25 2100);
FORCEPROP 1 LAST HDL_TAP TRUE
J 2
(-350 1925);
DISPLAY 0.872340 (-350 1925);
DISPLAY INVISIBLE (-350 1925);
FORCEPROP 1 LAST PATH I52
J 2
(-23 2050);
DISPLAY 0.872340 (-23 2050);
PAINT GREEN (-23 2050);
DISPLAY INVISIBLE (-23 2050);
FORCEADD TAP..1
R 2
(-25 2100);
FORCEPROP 3 LASTPIN (25 2100) SIG_NAME M_D_CPU0_SA_CB<3>
J 0
(35 2110);
DISPLAY 0.659574 (35 2110);
PAINT MONO (35 2110);
DISPLAY INVISIBLE (35 2110);
FORCEPROP 1 LASTPIN (25 2100) BN 3
J 2
(37 2108);
DISPLAY 0.680851 (37 2108);
PAINT GREEN (37 2108);
FORCEPROP 2 LAST CDS_LIB standard
J 0
(-25 2100);
DISPLAY INVISIBLE (-25 2100);
FORCEPROP 1 LAST BODY_TYPE PLUMBING
J 2
(-25 2150);
DISPLAY 0.872340 (-25 2150);
PAINT GREEN (-25 2150);
DISPLAY INVISIBLE (-25 2150);
FORCEPROP 1 LAST HDL_TAP TRUE
J 2
(-350 1975);
DISPLAY 0.872340 (-350 1975);
DISPLAY INVISIBLE (-350 1975);
FORCEPROP 1 LAST PATH I53
J 2
(-23 2100);
DISPLAY 0.872340 (-23 2100);
PAINT GREEN (-23 2100);
DISPLAY INVISIBLE (-23 2100);
FORCEADD TAP..1
R 2
(-25 2150);
FORCEPROP 3 LASTPIN (25 2150) SIG_NAME M_D_CPU0_SA_CB<4>
J 0
(35 2160);
DISPLAY 0.659574 (35 2160);
PAINT MONO (35 2160);
DISPLAY INVISIBLE (35 2160);
FORCEPROP 1 LASTPIN (25 2150) BN 4
J 2
(37 2158);
DISPLAY 0.680851 (37 2158);
PAINT GREEN (37 2158);
FORCEPROP 2 LAST CDS_LIB standard
J 0
(-25 2150);
DISPLAY INVISIBLE (-25 2150);
FORCEPROP 1 LAST BODY_TYPE PLUMBING
J 2
(-25 2200);
DISPLAY 0.872340 (-25 2200);
PAINT GREEN (-25 2200);
DISPLAY INVISIBLE (-25 2200);
FORCEPROP 1 LAST HDL_TAP TRUE
J 2
(-350 2025);
DISPLAY 0.872340 (-350 2025);
DISPLAY INVISIBLE (-350 2025);
FORCEPROP 1 LAST PATH I54
J 2
(-23 2150);
DISPLAY 0.872340 (-23 2150);
PAINT GREEN (-23 2150);
DISPLAY INVISIBLE (-23 2150);
FORCEADD TAP..1
R 2
(-25 2200);
FORCEPROP 3 LASTPIN (25 2200) SIG_NAME M_D_CPU0_SA_CB<5>
J 0
(35 2210);
DISPLAY 0.659574 (35 2210);
PAINT MONO (35 2210);
DISPLAY INVISIBLE (35 2210);
FORCEPROP 1 LASTPIN (25 2200) BN 5
J 2
(37 2208);
DISPLAY 0.680851 (37 2208);
PAINT GREEN (37 2208);
FORCEPROP 2 LAST CDS_LIB standard
J 0
(-25 2200);
DISPLAY INVISIBLE (-25 2200);
FORCEPROP 1 LAST BODY_TYPE PLUMBING
J 2
(-25 2250);
DISPLAY 0.872340 (-25 2250);
PAINT GREEN (-25 2250);
DISPLAY INVISIBLE (-25 2250);
FORCEPROP 1 LAST HDL_TAP TRUE
J 2
(-350 2075);
DISPLAY 0.872340 (-350 2075);
DISPLAY INVISIBLE (-350 2075);
FORCEPROP 1 LAST PATH I55
J 2
(-23 2200);
DISPLAY 0.872340 (-23 2200);
PAINT GREEN (-23 2200);
DISPLAY INVISIBLE (-23 2200);
FORCEADD TAP..1
R 2
(-25 2250);
FORCEPROP 3 LASTPIN (25 2250) SIG_NAME M_D_CPU0_SA_CB<6>
J 0
(35 2260);
DISPLAY 0.659574 (35 2260);
PAINT MONO (35 2260);
DISPLAY INVISIBLE (35 2260);
FORCEPROP 1 LASTPIN (25 2250) BN 6
J 2
(37 2258);
DISPLAY 0.680851 (37 2258);
PAINT GREEN (37 2258);
FORCEPROP 2 LAST CDS_LIB standard
J 0
(-25 2250);
DISPLAY INVISIBLE (-25 2250);
FORCEPROP 1 LAST BODY_TYPE PLUMBING
J 2
(-25 2300);
DISPLAY 0.872340 (-25 2300);
PAINT GREEN (-25 2300);
DISPLAY INVISIBLE (-25 2300);
FORCEPROP 1 LAST HDL_TAP TRUE
J 2
(-350 2125);
DISPLAY 0.872340 (-350 2125);
DISPLAY INVISIBLE (-350 2125);
FORCEPROP 1 LAST PATH I56
J 2
(-23 2250);
DISPLAY 0.872340 (-23 2250);
PAINT GREEN (-23 2250);
DISPLAY INVISIBLE (-23 2250);
FORCEADD OFFPAGE..3
R 2
(-1050 3925);
FORCEPROP 2 LAST $XR1 89 
J 0
(-1419 3925);
DISPLAY 0.638298 (-1419 3925);
PAINT MONO (-1419 3925);
FORCEPROP 2 LAST $XR0 88 
J 0
(-1329 3925);
DISPLAY 0.638298 (-1329 3925);
PAINT MONO (-1329 3925);
FORCEPROP 2 LAST CDS_LIB standard
J 0
(-1050 3925);
DISPLAY INVISIBLE (-1050 3925);
FORCEPROP 1 LAST OFFPAGE TRUE
J 2
(-1375 3800);
DISPLAY 0.872340 (-1375 3800);
DISPLAY INVISIBLE (-1375 3800);
FORCEPROP 1 LAST COMMENT_BODY TRUE
J 2
(-1000 3825);
DISPLAY 0.872340 (-1000 3825);
PAINT GREEN (-1000 3825);
DISPLAY INVISIBLE (-1000 3825);
FORCEPROP 2 LAST PATH I57
J 0
(-1000 4000);
DISPLAY 1.021277 (-1000 4000);
DISPLAY INVISIBLE (-1000 4000);
FORCEADD TAP..1
R 2
(-25 2300);
FORCEPROP 3 LASTPIN (25 2300) SIG_NAME M_D_CPU0_SA_CB<7>
J 0
(35 2310);
DISPLAY 0.659574 (35 2310);
PAINT MONO (35 2310);
DISPLAY INVISIBLE (35 2310);
FORCEPROP 1 LASTPIN (25 2300) BN 7
J 2
(37 2308);
DISPLAY 0.680851 (37 2308);
PAINT GREEN (37 2308);
FORCEPROP 2 LAST CDS_LIB standard
J 0
(-25 2300);
DISPLAY INVISIBLE (-25 2300);
FORCEPROP 1 LAST BODY_TYPE PLUMBING
J 2
(-25 2350);
DISPLAY 0.872340 (-25 2350);
PAINT GREEN (-25 2350);
DISPLAY INVISIBLE (-25 2350);
FORCEPROP 1 LAST HDL_TAP TRUE
J 2
(-350 2175);
DISPLAY 0.872340 (-350 2175);
DISPLAY INVISIBLE (-350 2175);
FORCEPROP 1 LAST PATH I58
J 2
(-23 2300);
DISPLAY 0.872340 (-23 2300);
PAINT GREEN (-23 2300);
DISPLAY INVISIBLE (-23 2300);
FORCEADD TAP..1
R 2
(-25 2350);
FORCEPROP 3 LASTPIN (25 2350) SIG_NAME M_D_CPU0_SA_DQ<0>
J 0
(35 2360);
DISPLAY 0.659574 (35 2360);
PAINT MONO (35 2360);
DISPLAY INVISIBLE (35 2360);
FORCEPROP 1 LASTPIN (25 2350) BN 0
J 2
(37 2358);
DISPLAY 0.680851 (37 2358);
PAINT GREEN (37 2358);
FORCEPROP 2 LAST CDS_LIB standard
J 0
(-25 2350);
DISPLAY INVISIBLE (-25 2350);
FORCEPROP 1 LAST BODY_TYPE PLUMBING
J 2
(-25 2400);
DISPLAY 0.872340 (-25 2400);
PAINT GREEN (-25 2400);
DISPLAY INVISIBLE (-25 2400);
FORCEPROP 1 LAST HDL_TAP TRUE
J 2
(-350 2225);
DISPLAY 0.872340 (-350 2225);
DISPLAY INVISIBLE (-350 2225);
FORCEPROP 1 LAST PATH I59
J 2
(-23 2350);
DISPLAY 0.872340 (-23 2350);
PAINT GREEN (-23 2350);
DISPLAY INVISIBLE (-23 2350);
FORCEADD TAP..1
R 2
(-25 -150);
FORCEPROP 3 LASTPIN (25 -150) SIG_NAME M_D_CPU0_CLK_DP<1>
J 0
(35 -140);
DISPLAY 0.659574 (35 -140);
PAINT MONO (35 -140);
DISPLAY INVISIBLE (35 -140);
FORCEPROP 1 LASTPIN (25 -150) BN 1
J 2
(37 -142);
DISPLAY 0.680851 (37 -142);
PAINT GREEN (37 -142);
FORCEPROP 2 LAST CDS_LIB standard
J 0
(-25 -150);
DISPLAY INVISIBLE (-25 -150);
FORCEPROP 1 LAST BODY_TYPE PLUMBING
J 2
(-25 -100);
DISPLAY 0.872340 (-25 -100);
PAINT GREEN (-25 -100);
DISPLAY INVISIBLE (-25 -100);
FORCEPROP 1 LAST HDL_TAP TRUE
J 2
(-350 -275);
DISPLAY 0.872340 (-350 -275);
DISPLAY INVISIBLE (-350 -275);
FORCEPROP 1 LAST PATH I6
J 2
(-23 -150);
DISPLAY 0.872340 (-23 -150);
PAINT GREEN (-23 -150);
DISPLAY INVISIBLE (-23 -150);
FORCEADD TAP..1
R 2
(-25 2400);
FORCEPROP 3 LASTPIN (25 2400) SIG_NAME M_D_CPU0_SA_DQ<1>
J 0
(35 2410);
DISPLAY 0.659574 (35 2410);
PAINT MONO (35 2410);
DISPLAY INVISIBLE (35 2410);
FORCEPROP 1 LASTPIN (25 2400) BN 1
J 2
(37 2408);
DISPLAY 0.680851 (37 2408);
PAINT GREEN (37 2408);
FORCEPROP 2 LAST CDS_LIB standard
J 0
(-25 2400);
DISPLAY INVISIBLE (-25 2400);
FORCEPROP 1 LAST BODY_TYPE PLUMBING
J 2
(-25 2450);
DISPLAY 0.872340 (-25 2450);
PAINT GREEN (-25 2450);
DISPLAY INVISIBLE (-25 2450);
FORCEPROP 1 LAST HDL_TAP TRUE
J 2
(-350 2275);
DISPLAY 0.872340 (-350 2275);
DISPLAY INVISIBLE (-350 2275);
FORCEPROP 1 LAST PATH I60
J 2
(-23 2400);
DISPLAY 0.872340 (-23 2400);
PAINT GREEN (-23 2400);
DISPLAY INVISIBLE (-23 2400);
FORCEADD TAP..1
R 2
(-25 2450);
FORCEPROP 3 LASTPIN (25 2450) SIG_NAME M_D_CPU0_SA_DQ<2>
J 0
(35 2460);
DISPLAY 0.659574 (35 2460);
PAINT MONO (35 2460);
DISPLAY INVISIBLE (35 2460);
FORCEPROP 1 LASTPIN (25 2450) BN 2
J 2
(37 2458);
DISPLAY 0.680851 (37 2458);
PAINT GREEN (37 2458);
FORCEPROP 2 LAST CDS_LIB standard
J 0
(-25 2450);
DISPLAY INVISIBLE (-25 2450);
FORCEPROP 1 LAST BODY_TYPE PLUMBING
J 2
(-25 2500);
DISPLAY 0.872340 (-25 2500);
PAINT GREEN (-25 2500);
DISPLAY INVISIBLE (-25 2500);
FORCEPROP 1 LAST HDL_TAP TRUE
J 2
(-350 2325);
DISPLAY 0.872340 (-350 2325);
DISPLAY INVISIBLE (-350 2325);
FORCEPROP 1 LAST PATH I61
J 2
(-23 2450);
DISPLAY 0.872340 (-23 2450);
PAINT GREEN (-23 2450);
DISPLAY INVISIBLE (-23 2450);
FORCEADD TAP..1
R 2
(-25 2500);
FORCEPROP 3 LASTPIN (25 2500) SIG_NAME M_D_CPU0_SA_DQ<3>
J 0
(35 2510);
DISPLAY 0.659574 (35 2510);
PAINT MONO (35 2510);
DISPLAY INVISIBLE (35 2510);
FORCEPROP 1 LASTPIN (25 2500) BN 3
J 2
(37 2508);
DISPLAY 0.680851 (37 2508);
PAINT GREEN (37 2508);
FORCEPROP 2 LAST CDS_LIB standard
J 0
(-25 2500);
DISPLAY INVISIBLE (-25 2500);
FORCEPROP 1 LAST BODY_TYPE PLUMBING
J 2
(-25 2550);
DISPLAY 0.872340 (-25 2550);
PAINT GREEN (-25 2550);
DISPLAY INVISIBLE (-25 2550);
FORCEPROP 1 LAST HDL_TAP TRUE
J 2
(-350 2375);
DISPLAY 0.872340 (-350 2375);
DISPLAY INVISIBLE (-350 2375);
FORCEPROP 1 LAST PATH I62
J 2
(-23 2500);
DISPLAY 0.872340 (-23 2500);
PAINT GREEN (-23 2500);
DISPLAY INVISIBLE (-23 2500);
FORCEADD TAP..1
R 2
(-25 2550);
FORCEPROP 3 LASTPIN (25 2550) SIG_NAME M_D_CPU0_SA_DQ<4>
J 0
(35 2560);
DISPLAY 0.659574 (35 2560);
PAINT MONO (35 2560);
DISPLAY INVISIBLE (35 2560);
FORCEPROP 1 LASTPIN (25 2550) BN 4
J 2
(37 2558);
DISPLAY 0.680851 (37 2558);
PAINT GREEN (37 2558);
FORCEPROP 2 LAST CDS_LIB standard
J 0
(-25 2550);
DISPLAY INVISIBLE (-25 2550);
FORCEPROP 1 LAST BODY_TYPE PLUMBING
J 2
(-25 2600);
DISPLAY 0.872340 (-25 2600);
PAINT GREEN (-25 2600);
DISPLAY INVISIBLE (-25 2600);
FORCEPROP 1 LAST HDL_TAP TRUE
J 2
(-350 2425);
DISPLAY 0.872340 (-350 2425);
DISPLAY INVISIBLE (-350 2425);
FORCEPROP 1 LAST PATH I63
J 2
(-23 2550);
DISPLAY 0.872340 (-23 2550);
PAINT GREEN (-23 2550);
DISPLAY INVISIBLE (-23 2550);
FORCEADD TAP..1
R 2
(-25 2600);
FORCEPROP 3 LASTPIN (25 2600) SIG_NAME M_D_CPU0_SA_DQ<5>
J 0
(35 2610);
DISPLAY 0.659574 (35 2610);
PAINT MONO (35 2610);
DISPLAY INVISIBLE (35 2610);
FORCEPROP 1 LASTPIN (25 2600) BN 5
J 2
(37 2608);
DISPLAY 0.680851 (37 2608);
PAINT GREEN (37 2608);
FORCEPROP 2 LAST CDS_LIB standard
J 0
(-25 2600);
DISPLAY INVISIBLE (-25 2600);
FORCEPROP 1 LAST BODY_TYPE PLUMBING
J 2
(-25 2650);
DISPLAY 0.872340 (-25 2650);
PAINT GREEN (-25 2650);
DISPLAY INVISIBLE (-25 2650);
FORCEPROP 1 LAST HDL_TAP TRUE
J 2
(-350 2475);
DISPLAY 0.872340 (-350 2475);
DISPLAY INVISIBLE (-350 2475);
FORCEPROP 1 LAST PATH I64
J 2
(-23 2600);
DISPLAY 0.872340 (-23 2600);
PAINT GREEN (-23 2600);
DISPLAY INVISIBLE (-23 2600);
FORCEADD TAP..1
R 2
(-25 2650);
FORCEPROP 3 LASTPIN (25 2650) SIG_NAME M_D_CPU0_SA_DQ<6>
J 0
(35 2660);
DISPLAY 0.659574 (35 2660);
PAINT MONO (35 2660);
DISPLAY INVISIBLE (35 2660);
FORCEPROP 1 LASTPIN (25 2650) BN 6
J 2
(37 2658);
DISPLAY 0.680851 (37 2658);
PAINT GREEN (37 2658);
FORCEPROP 2 LAST CDS_LIB standard
J 0
(-25 2650);
DISPLAY INVISIBLE (-25 2650);
FORCEPROP 1 LAST BODY_TYPE PLUMBING
J 2
(-25 2700);
DISPLAY 0.872340 (-25 2700);
PAINT GREEN (-25 2700);
DISPLAY INVISIBLE (-25 2700);
FORCEPROP 1 LAST HDL_TAP TRUE
J 2
(-350 2525);
DISPLAY 0.872340 (-350 2525);
DISPLAY INVISIBLE (-350 2525);
FORCEPROP 1 LAST PATH I65
J 2
(-23 2650);
DISPLAY 0.872340 (-23 2650);
PAINT GREEN (-23 2650);
DISPLAY INVISIBLE (-23 2650);
FORCEADD TAP..1
R 2
(-25 2700);
FORCEPROP 3 LASTPIN (25 2700) SIG_NAME M_D_CPU0_SA_DQ<7>
J 0
(35 2710);
DISPLAY 0.659574 (35 2710);
PAINT MONO (35 2710);
DISPLAY INVISIBLE (35 2710);
FORCEPROP 1 LASTPIN (25 2700) BN 7
J 2
(37 2708);
DISPLAY 0.680851 (37 2708);
PAINT GREEN (37 2708);
FORCEPROP 2 LAST CDS_LIB standard
J 0
(-25 2700);
DISPLAY INVISIBLE (-25 2700);
FORCEPROP 1 LAST BODY_TYPE PLUMBING
J 2
(-25 2750);
DISPLAY 0.872340 (-25 2750);
PAINT GREEN (-25 2750);
DISPLAY INVISIBLE (-25 2750);
FORCEPROP 1 LAST HDL_TAP TRUE
J 2
(-350 2575);
DISPLAY 0.872340 (-350 2575);
DISPLAY INVISIBLE (-350 2575);
FORCEPROP 1 LAST PATH I66
J 2
(-23 2700);
DISPLAY 0.872340 (-23 2700);
PAINT GREEN (-23 2700);
DISPLAY INVISIBLE (-23 2700);
FORCEADD TAP..1
R 2
(-25 2750);
FORCEPROP 3 LASTPIN (25 2750) SIG_NAME M_D_CPU0_SA_DQ<8>
J 0
(35 2760);
DISPLAY 0.659574 (35 2760);
PAINT MONO (35 2760);
DISPLAY INVISIBLE (35 2760);
FORCEPROP 1 LASTPIN (25 2750) BN 8
J 2
(37 2758);
DISPLAY 0.680851 (37 2758);
PAINT GREEN (37 2758);
FORCEPROP 2 LAST CDS_LIB standard
J 0
(-25 2750);
DISPLAY INVISIBLE (-25 2750);
FORCEPROP 1 LAST BODY_TYPE PLUMBING
J 2
(-25 2800);
DISPLAY 0.872340 (-25 2800);
PAINT GREEN (-25 2800);
DISPLAY INVISIBLE (-25 2800);
FORCEPROP 1 LAST HDL_TAP TRUE
J 2
(-350 2625);
DISPLAY 0.872340 (-350 2625);
DISPLAY INVISIBLE (-350 2625);
FORCEPROP 1 LAST PATH I67
J 2
(-23 2750);
DISPLAY 0.872340 (-23 2750);
PAINT GREEN (-23 2750);
DISPLAY INVISIBLE (-23 2750);
FORCEADD TAP..1
R 2
(-25 2800);
FORCEPROP 3 LASTPIN (25 2800) SIG_NAME M_D_CPU0_SA_DQ<9>
J 0
(35 2810);
DISPLAY 0.659574 (35 2810);
PAINT MONO (35 2810);
DISPLAY INVISIBLE (35 2810);
FORCEPROP 1 LASTPIN (25 2800) BN 9
J 2
(37 2808);
DISPLAY 0.680851 (37 2808);
PAINT GREEN (37 2808);
FORCEPROP 2 LAST CDS_LIB standard
J 0
(-25 2800);
DISPLAY INVISIBLE (-25 2800);
FORCEPROP 1 LAST BODY_TYPE PLUMBING
J 2
(-25 2850);
DISPLAY 0.872340 (-25 2850);
PAINT GREEN (-25 2850);
DISPLAY INVISIBLE (-25 2850);
FORCEPROP 1 LAST HDL_TAP TRUE
J 2
(-350 2675);
DISPLAY 0.872340 (-350 2675);
DISPLAY INVISIBLE (-350 2675);
FORCEPROP 1 LAST PATH I68
J 2
(-23 2800);
DISPLAY 0.872340 (-23 2800);
PAINT GREEN (-23 2800);
DISPLAY INVISIBLE (-23 2800);
FORCEADD TAP..1
R 2
(-25 2850);
FORCEPROP 3 LASTPIN (25 2850) SIG_NAME M_D_CPU0_SA_DQ<10>
J 0
(35 2860);
DISPLAY 0.659574 (35 2860);
PAINT MONO (35 2860);
DISPLAY INVISIBLE (35 2860);
FORCEPROP 1 LASTPIN (25 2850) BN 10
J 2
(37 2858);
DISPLAY 0.680851 (37 2858);
PAINT GREEN (37 2858);
FORCEPROP 2 LAST CDS_LIB standard
J 0
(-25 2850);
DISPLAY INVISIBLE (-25 2850);
FORCEPROP 1 LAST BODY_TYPE PLUMBING
J 2
(-25 2900);
DISPLAY 0.872340 (-25 2900);
PAINT GREEN (-25 2900);
DISPLAY INVISIBLE (-25 2900);
FORCEPROP 1 LAST HDL_TAP TRUE
J 2
(-350 2725);
DISPLAY 0.872340 (-350 2725);
DISPLAY INVISIBLE (-350 2725);
FORCEPROP 1 LAST PATH I69
J 2
(-23 2850);
DISPLAY 0.872340 (-23 2850);
PAINT GREEN (-23 2850);
DISPLAY INVISIBLE (-23 2850);
FORCEADD TAP..1
R 2
(-25 -250);
FORCEPROP 3 LASTPIN (25 -250) SIG_NAME M_D_CPU0_CLK_DN<1>
J 0
(35 -240);
DISPLAY 0.659574 (35 -240);
PAINT MONO (35 -240);
DISPLAY INVISIBLE (35 -240);
FORCEPROP 1 LASTPIN (25 -250) BN 1
J 2
(37 -242);
DISPLAY 0.680851 (37 -242);
PAINT GREEN (37 -242);
FORCEPROP 2 LAST CDS_LIB standard
J 0
(-25 -250);
DISPLAY INVISIBLE (-25 -250);
FORCEPROP 1 LAST BODY_TYPE PLUMBING
J 2
(-25 -200);
DISPLAY 0.872340 (-25 -200);
PAINT GREEN (-25 -200);
DISPLAY INVISIBLE (-25 -200);
FORCEPROP 1 LAST HDL_TAP TRUE
J 2
(-350 -375);
DISPLAY 0.872340 (-350 -375);
DISPLAY INVISIBLE (-350 -375);
FORCEPROP 1 LAST PATH I7
J 2
(-23 -250);
DISPLAY 0.872340 (-23 -250);
PAINT GREEN (-23 -250);
DISPLAY INVISIBLE (-23 -250);
FORCEADD TAP..1
R 2
(-25 2900);
FORCEPROP 3 LASTPIN (25 2900) SIG_NAME M_D_CPU0_SA_DQ<11>
J 0
(35 2910);
DISPLAY 0.659574 (35 2910);
PAINT MONO (35 2910);
DISPLAY INVISIBLE (35 2910);
FORCEPROP 1 LASTPIN (25 2900) BN 11
J 2
(37 2908);
DISPLAY 0.680851 (37 2908);
PAINT GREEN (37 2908);
FORCEPROP 2 LAST CDS_LIB standard
J 0
(-25 2900);
DISPLAY INVISIBLE (-25 2900);
FORCEPROP 1 LAST BODY_TYPE PLUMBING
J 2
(-25 2950);
DISPLAY 0.872340 (-25 2950);
PAINT GREEN (-25 2950);
DISPLAY INVISIBLE (-25 2950);
FORCEPROP 1 LAST HDL_TAP TRUE
J 2
(-350 2775);
DISPLAY 0.872340 (-350 2775);
DISPLAY INVISIBLE (-350 2775);
FORCEPROP 1 LAST PATH I70
J 2
(-23 2900);
DISPLAY 0.872340 (-23 2900);
PAINT GREEN (-23 2900);
DISPLAY INVISIBLE (-23 2900);
FORCEADD TAP..1
R 2
(-25 2950);
FORCEPROP 3 LASTPIN (25 2950) SIG_NAME M_D_CPU0_SA_DQ<12>
J 0
(35 2960);
DISPLAY 0.659574 (35 2960);
PAINT MONO (35 2960);
DISPLAY INVISIBLE (35 2960);
FORCEPROP 1 LASTPIN (25 2950) BN 12
J 2
(37 2958);
DISPLAY 0.680851 (37 2958);
PAINT GREEN (37 2958);
FORCEPROP 2 LAST CDS_LIB standard
J 0
(-25 2950);
DISPLAY INVISIBLE (-25 2950);
FORCEPROP 1 LAST BODY_TYPE PLUMBING
J 2
(-25 3000);
DISPLAY 0.872340 (-25 3000);
PAINT GREEN (-25 3000);
DISPLAY INVISIBLE (-25 3000);
FORCEPROP 1 LAST HDL_TAP TRUE
J 2
(-350 2825);
DISPLAY 0.872340 (-350 2825);
DISPLAY INVISIBLE (-350 2825);
FORCEPROP 1 LAST PATH I71
J 2
(-23 2950);
DISPLAY 0.872340 (-23 2950);
PAINT GREEN (-23 2950);
DISPLAY INVISIBLE (-23 2950);
FORCEADD TAP..1
R 2
(-25 3000);
FORCEPROP 3 LASTPIN (25 3000) SIG_NAME M_D_CPU0_SA_DQ<13>
J 0
(35 3010);
DISPLAY 0.659574 (35 3010);
PAINT MONO (35 3010);
DISPLAY INVISIBLE (35 3010);
FORCEPROP 1 LASTPIN (25 3000) BN 13
J 2
(37 3008);
DISPLAY 0.680851 (37 3008);
PAINT GREEN (37 3008);
FORCEPROP 2 LAST CDS_LIB standard
J 0
(-25 3000);
DISPLAY INVISIBLE (-25 3000);
FORCEPROP 1 LAST BODY_TYPE PLUMBING
J 2
(-25 3050);
DISPLAY 0.872340 (-25 3050);
PAINT GREEN (-25 3050);
DISPLAY INVISIBLE (-25 3050);
FORCEPROP 1 LAST HDL_TAP TRUE
J 2
(-350 2875);
DISPLAY 0.872340 (-350 2875);
DISPLAY INVISIBLE (-350 2875);
FORCEPROP 1 LAST PATH I72
J 2
(-23 3000);
DISPLAY 0.872340 (-23 3000);
PAINT GREEN (-23 3000);
DISPLAY INVISIBLE (-23 3000);
FORCEADD TAP..1
R 2
(-25 3050);
FORCEPROP 3 LASTPIN (25 3050) SIG_NAME M_D_CPU0_SA_DQ<14>
J 0
(35 3060);
DISPLAY 0.659574 (35 3060);
PAINT MONO (35 3060);
DISPLAY INVISIBLE (35 3060);
FORCEPROP 1 LASTPIN (25 3050) BN 14
J 2
(37 3058);
DISPLAY 0.680851 (37 3058);
PAINT GREEN (37 3058);
FORCEPROP 2 LAST CDS_LIB standard
J 0
(-25 3050);
DISPLAY INVISIBLE (-25 3050);
FORCEPROP 1 LAST BODY_TYPE PLUMBING
J 2
(-25 3100);
DISPLAY 0.872340 (-25 3100);
PAINT GREEN (-25 3100);
DISPLAY INVISIBLE (-25 3100);
FORCEPROP 1 LAST HDL_TAP TRUE
J 2
(-350 2925);
DISPLAY 0.872340 (-350 2925);
DISPLAY INVISIBLE (-350 2925);
FORCEPROP 1 LAST PATH I73
J 2
(-23 3050);
DISPLAY 0.872340 (-23 3050);
PAINT GREEN (-23 3050);
DISPLAY INVISIBLE (-23 3050);
FORCEADD TAP..1
R 2
(-25 3100);
FORCEPROP 3 LASTPIN (25 3100) SIG_NAME M_D_CPU0_SA_DQ<15>
J 0
(35 3110);
DISPLAY 0.659574 (35 3110);
PAINT MONO (35 3110);
DISPLAY INVISIBLE (35 3110);
FORCEPROP 1 LASTPIN (25 3100) BN 15
J 2
(37 3108);
DISPLAY 0.680851 (37 3108);
PAINT GREEN (37 3108);
FORCEPROP 2 LAST CDS_LIB standard
J 0
(-25 3100);
DISPLAY INVISIBLE (-25 3100);
FORCEPROP 1 LAST BODY_TYPE PLUMBING
J 2
(-25 3150);
DISPLAY 0.872340 (-25 3150);
PAINT GREEN (-25 3150);
DISPLAY INVISIBLE (-25 3150);
FORCEPROP 1 LAST HDL_TAP TRUE
J 2
(-350 2975);
DISPLAY 0.872340 (-350 2975);
DISPLAY INVISIBLE (-350 2975);
FORCEPROP 1 LAST PATH I74
J 2
(-23 3100);
DISPLAY 0.872340 (-23 3100);
PAINT GREEN (-23 3100);
DISPLAY INVISIBLE (-23 3100);
FORCEADD TAP..1
R 2
(-25 3150);
FORCEPROP 3 LASTPIN (25 3150) SIG_NAME M_D_CPU0_SA_DQ<16>
J 0
(35 3160);
DISPLAY 0.659574 (35 3160);
PAINT MONO (35 3160);
DISPLAY INVISIBLE (35 3160);
FORCEPROP 1 LASTPIN (25 3150) BN 16
J 2
(37 3158);
DISPLAY 0.680851 (37 3158);
PAINT GREEN (37 3158);
FORCEPROP 2 LAST CDS_LIB standard
J 0
(-25 3150);
DISPLAY INVISIBLE (-25 3150);
FORCEPROP 1 LAST BODY_TYPE PLUMBING
J 2
(-25 3200);
DISPLAY 0.872340 (-25 3200);
PAINT GREEN (-25 3200);
DISPLAY INVISIBLE (-25 3200);
FORCEPROP 1 LAST HDL_TAP TRUE
J 2
(-350 3025);
DISPLAY 0.872340 (-350 3025);
DISPLAY INVISIBLE (-350 3025);
FORCEPROP 1 LAST PATH I75
J 2
(-23 3150);
DISPLAY 0.872340 (-23 3150);
PAINT GREEN (-23 3150);
DISPLAY INVISIBLE (-23 3150);
FORCEADD TAP..1
R 2
(-25 3200);
FORCEPROP 3 LASTPIN (25 3200) SIG_NAME M_D_CPU0_SA_DQ<17>
J 0
(35 3210);
DISPLAY 0.659574 (35 3210);
PAINT MONO (35 3210);
DISPLAY INVISIBLE (35 3210);
FORCEPROP 1 LASTPIN (25 3200) BN 17
J 2
(37 3208);
DISPLAY 0.680851 (37 3208);
PAINT GREEN (37 3208);
FORCEPROP 2 LAST CDS_LIB standard
J 0
(-25 3200);
DISPLAY INVISIBLE (-25 3200);
FORCEPROP 1 LAST BODY_TYPE PLUMBING
J 2
(-25 3250);
DISPLAY 0.872340 (-25 3250);
PAINT GREEN (-25 3250);
DISPLAY INVISIBLE (-25 3250);
FORCEPROP 1 LAST HDL_TAP TRUE
J 2
(-350 3075);
DISPLAY 0.872340 (-350 3075);
DISPLAY INVISIBLE (-350 3075);
FORCEPROP 1 LAST PATH I76
J 2
(-23 3200);
DISPLAY 0.872340 (-23 3200);
PAINT GREEN (-23 3200);
DISPLAY INVISIBLE (-23 3200);
FORCEADD TAP..1
R 2
(-25 3250);
FORCEPROP 3 LASTPIN (25 3250) SIG_NAME M_D_CPU0_SA_DQ<18>
J 0
(35 3260);
DISPLAY 0.659574 (35 3260);
PAINT MONO (35 3260);
DISPLAY INVISIBLE (35 3260);
FORCEPROP 1 LASTPIN (25 3250) BN 18
J 2
(37 3258);
DISPLAY 0.680851 (37 3258);
PAINT GREEN (37 3258);
FORCEPROP 2 LAST CDS_LIB standard
J 0
(-25 3250);
DISPLAY INVISIBLE (-25 3250);
FORCEPROP 1 LAST BODY_TYPE PLUMBING
J 2
(-25 3300);
DISPLAY 0.872340 (-25 3300);
PAINT GREEN (-25 3300);
DISPLAY INVISIBLE (-25 3300);
FORCEPROP 1 LAST HDL_TAP TRUE
J 2
(-350 3125);
DISPLAY 0.872340 (-350 3125);
DISPLAY INVISIBLE (-350 3125);
FORCEPROP 1 LAST PATH I77
J 2
(-23 3250);
DISPLAY 0.872340 (-23 3250);
PAINT GREEN (-23 3250);
DISPLAY INVISIBLE (-23 3250);
FORCEADD TAP..1
R 2
(-25 3300);
FORCEPROP 3 LASTPIN (25 3300) SIG_NAME M_D_CPU0_SA_DQ<19>
J 0
(35 3310);
DISPLAY 0.659574 (35 3310);
PAINT MONO (35 3310);
DISPLAY INVISIBLE (35 3310);
FORCEPROP 1 LASTPIN (25 3300) BN 19
J 2
(37 3308);
DISPLAY 0.680851 (37 3308);
PAINT GREEN (37 3308);
FORCEPROP 2 LAST CDS_LIB standard
J 0
(-25 3300);
DISPLAY INVISIBLE (-25 3300);
FORCEPROP 1 LAST BODY_TYPE PLUMBING
J 2
(-25 3350);
DISPLAY 0.872340 (-25 3350);
PAINT GREEN (-25 3350);
DISPLAY INVISIBLE (-25 3350);
FORCEPROP 1 LAST HDL_TAP TRUE
J 2
(-350 3175);
DISPLAY 0.872340 (-350 3175);
DISPLAY INVISIBLE (-350 3175);
FORCEPROP 1 LAST PATH I78
J 2
(-23 3300);
DISPLAY 0.872340 (-23 3300);
PAINT GREEN (-23 3300);
DISPLAY INVISIBLE (-23 3300);
FORCEADD TAP..1
R 2
(-25 3350);
FORCEPROP 3 LASTPIN (25 3350) SIG_NAME M_D_CPU0_SA_DQ<20>
J 0
(35 3360);
DISPLAY 0.659574 (35 3360);
PAINT MONO (35 3360);
DISPLAY INVISIBLE (35 3360);
FORCEPROP 1 LASTPIN (25 3350) BN 20
J 2
(37 3358);
DISPLAY 0.680851 (37 3358);
PAINT GREEN (37 3358);
FORCEPROP 2 LAST CDS_LIB standard
J 0
(-25 3350);
DISPLAY INVISIBLE (-25 3350);
FORCEPROP 1 LAST BODY_TYPE PLUMBING
J 2
(-25 3400);
DISPLAY 0.872340 (-25 3400);
PAINT GREEN (-25 3400);
DISPLAY INVISIBLE (-25 3400);
FORCEPROP 1 LAST HDL_TAP TRUE
J 2
(-350 3225);
DISPLAY 0.872340 (-350 3225);
DISPLAY INVISIBLE (-350 3225);
FORCEPROP 1 LAST PATH I79
J 2
(-23 3350);
DISPLAY 0.872340 (-23 3350);
PAINT GREEN (-23 3350);
DISPLAY INVISIBLE (-23 3350);
FORCEADD TAP..1
R 2
(-25 100);
FORCEPROP 3 LASTPIN (25 100) SIG_NAME M_D_CPU0_SB_CB<3>
J 0
(35 110);
DISPLAY 0.659574 (35 110);
PAINT MONO (35 110);
DISPLAY INVISIBLE (35 110);
FORCEPROP 1 LASTPIN (25 100) BN 3
J 2
(37 108);
DISPLAY 0.680851 (37 108);
PAINT GREEN (37 108);
FORCEPROP 2 LAST CDS_LIB standard
J 0
(-25 100);
DISPLAY INVISIBLE (-25 100);
FORCEPROP 1 LAST BODY_TYPE PLUMBING
J 2
(-25 150);
DISPLAY 0.872340 (-25 150);
PAINT GREEN (-25 150);
DISPLAY INVISIBLE (-25 150);
FORCEPROP 1 LAST HDL_TAP TRUE
J 2
(-350 -25);
DISPLAY 0.872340 (-350 -25);
DISPLAY INVISIBLE (-350 -25);
FORCEPROP 1 LAST PATH I8
J 2
(-23 100);
DISPLAY 0.872340 (-23 100);
PAINT GREEN (-23 100);
DISPLAY INVISIBLE (-23 100);
FORCEADD TAP..1
R 2
(-25 3400);
FORCEPROP 3 LASTPIN (25 3400) SIG_NAME M_D_CPU0_SA_DQ<21>
J 0
(35 3410);
DISPLAY 0.659574 (35 3410);
PAINT MONO (35 3410);
DISPLAY INVISIBLE (35 3410);
FORCEPROP 1 LASTPIN (25 3400) BN 21
J 2
(37 3408);
DISPLAY 0.680851 (37 3408);
PAINT GREEN (37 3408);
FORCEPROP 2 LAST CDS_LIB standard
J 0
(-25 3400);
DISPLAY INVISIBLE (-25 3400);
FORCEPROP 1 LAST BODY_TYPE PLUMBING
J 2
(-25 3450);
DISPLAY 0.872340 (-25 3450);
PAINT GREEN (-25 3450);
DISPLAY INVISIBLE (-25 3450);
FORCEPROP 1 LAST HDL_TAP TRUE
J 2
(-350 3275);
DISPLAY 0.872340 (-350 3275);
DISPLAY INVISIBLE (-350 3275);
FORCEPROP 1 LAST PATH I80
J 2
(-23 3400);
DISPLAY 0.872340 (-23 3400);
PAINT GREEN (-23 3400);
DISPLAY INVISIBLE (-23 3400);
FORCEADD TAP..1
R 2
(-25 3450);
FORCEPROP 3 LASTPIN (25 3450) SIG_NAME M_D_CPU0_SA_DQ<22>
J 0
(35 3460);
DISPLAY 0.659574 (35 3460);
PAINT MONO (35 3460);
DISPLAY INVISIBLE (35 3460);
FORCEPROP 1 LASTPIN (25 3450) BN 22
J 2
(37 3458);
DISPLAY 0.680851 (37 3458);
PAINT GREEN (37 3458);
FORCEPROP 2 LAST CDS_LIB standard
J 0
(-25 3450);
DISPLAY INVISIBLE (-25 3450);
FORCEPROP 1 LAST BODY_TYPE PLUMBING
J 2
(-25 3500);
DISPLAY 0.872340 (-25 3500);
PAINT GREEN (-25 3500);
DISPLAY INVISIBLE (-25 3500);
FORCEPROP 1 LAST HDL_TAP TRUE
J 2
(-350 3325);
DISPLAY 0.872340 (-350 3325);
DISPLAY INVISIBLE (-350 3325);
FORCEPROP 1 LAST PATH I81
J 2
(-23 3450);
DISPLAY 0.872340 (-23 3450);
PAINT GREEN (-23 3450);
DISPLAY INVISIBLE (-23 3450);
FORCEADD TAP..1
R 2
(-25 3550);
FORCEPROP 3 LASTPIN (25 3550) SIG_NAME M_D_CPU0_SA_DQ<24>
J 0
(35 3560);
DISPLAY 0.659574 (35 3560);
PAINT MONO (35 3560);
DISPLAY INVISIBLE (35 3560);
FORCEPROP 1 LASTPIN (25 3550) BN 24
J 2
(37 3558);
DISPLAY 0.680851 (37 3558);
PAINT GREEN (37 3558);
FORCEPROP 2 LAST CDS_LIB standard
J 0
(-25 3550);
DISPLAY INVISIBLE (-25 3550);
FORCEPROP 1 LAST BODY_TYPE PLUMBING
J 2
(-25 3600);
DISPLAY 0.872340 (-25 3600);
PAINT GREEN (-25 3600);
DISPLAY INVISIBLE (-25 3600);
FORCEPROP 1 LAST HDL_TAP TRUE
J 2
(-350 3425);
DISPLAY 0.872340 (-350 3425);
DISPLAY INVISIBLE (-350 3425);
FORCEPROP 1 LAST PATH I82
J 2
(-23 3550);
DISPLAY 0.872340 (-23 3550);
PAINT GREEN (-23 3550);
DISPLAY INVISIBLE (-23 3550);
FORCEADD TAP..1
R 2
(-25 3500);
FORCEPROP 3 LASTPIN (25 3500) SIG_NAME M_D_CPU0_SA_DQ<23>
J 0
(35 3510);
DISPLAY 0.659574 (35 3510);
PAINT MONO (35 3510);
DISPLAY INVISIBLE (35 3510);
FORCEPROP 1 LASTPIN (25 3500) BN 23
J 2
(37 3508);
DISPLAY 0.680851 (37 3508);
PAINT GREEN (37 3508);
FORCEPROP 2 LAST CDS_LIB standard
J 0
(-25 3500);
DISPLAY INVISIBLE (-25 3500);
FORCEPROP 1 LAST BODY_TYPE PLUMBING
J 2
(-25 3550);
DISPLAY 0.872340 (-25 3550);
PAINT GREEN (-25 3550);
DISPLAY INVISIBLE (-25 3550);
FORCEPROP 1 LAST HDL_TAP TRUE
J 2
(-350 3375);
DISPLAY 0.872340 (-350 3375);
DISPLAY INVISIBLE (-350 3375);
FORCEPROP 1 LAST PATH I83
J 2
(-23 3500);
DISPLAY 0.872340 (-23 3500);
PAINT GREEN (-23 3500);
DISPLAY INVISIBLE (-23 3500);
FORCEADD TAP..1
R 2
(-25 3600);
FORCEPROP 3 LASTPIN (25 3600) SIG_NAME M_D_CPU0_SA_DQ<25>
J 0
(35 3610);
DISPLAY 0.659574 (35 3610);
PAINT MONO (35 3610);
DISPLAY INVISIBLE (35 3610);
FORCEPROP 1 LASTPIN (25 3600) BN 25
J 2
(37 3608);
DISPLAY 0.680851 (37 3608);
PAINT GREEN (37 3608);
FORCEPROP 2 LAST CDS_LIB standard
J 0
(-25 3600);
DISPLAY INVISIBLE (-25 3600);
FORCEPROP 1 LAST BODY_TYPE PLUMBING
J 2
(-25 3650);
DISPLAY 0.872340 (-25 3650);
PAINT GREEN (-25 3650);
DISPLAY INVISIBLE (-25 3650);
FORCEPROP 1 LAST HDL_TAP TRUE
J 2
(-350 3475);
DISPLAY 0.872340 (-350 3475);
DISPLAY INVISIBLE (-350 3475);
FORCEPROP 1 LAST PATH I84
J 2
(-23 3600);
DISPLAY 0.872340 (-23 3600);
PAINT GREEN (-23 3600);
DISPLAY INVISIBLE (-23 3600);
FORCEADD TAP..1
R 2
(-25 3700);
FORCEPROP 3 LASTPIN (25 3700) SIG_NAME M_D_CPU0_SA_DQ<27>
J 0
(35 3710);
DISPLAY 0.659574 (35 3710);
PAINT MONO (35 3710);
DISPLAY INVISIBLE (35 3710);
FORCEPROP 1 LASTPIN (25 3700) BN 27
J 2
(37 3708);
DISPLAY 0.680851 (37 3708);
PAINT GREEN (37 3708);
FORCEPROP 2 LAST CDS_LIB standard
J 0
(-25 3700);
DISPLAY INVISIBLE (-25 3700);
FORCEPROP 1 LAST BODY_TYPE PLUMBING
J 2
(-25 3750);
DISPLAY 0.872340 (-25 3750);
PAINT GREEN (-25 3750);
DISPLAY INVISIBLE (-25 3750);
FORCEPROP 1 LAST HDL_TAP TRUE
J 2
(-350 3575);
DISPLAY 0.872340 (-350 3575);
DISPLAY INVISIBLE (-350 3575);
FORCEPROP 1 LAST PATH I85
J 2
(-23 3700);
DISPLAY 0.872340 (-23 3700);
PAINT GREEN (-23 3700);
DISPLAY INVISIBLE (-23 3700);
FORCEADD TAP..1
R 2
(-25 3650);
FORCEPROP 3 LASTPIN (25 3650) SIG_NAME M_D_CPU0_SA_DQ<26>
J 0
(35 3660);
DISPLAY 0.659574 (35 3660);
PAINT MONO (35 3660);
DISPLAY INVISIBLE (35 3660);
FORCEPROP 1 LASTPIN (25 3650) BN 26
J 2
(37 3658);
DISPLAY 0.680851 (37 3658);
PAINT GREEN (37 3658);
FORCEPROP 2 LAST CDS_LIB standard
J 0
(-25 3650);
DISPLAY INVISIBLE (-25 3650);
FORCEPROP 1 LAST BODY_TYPE PLUMBING
J 2
(-25 3700);
DISPLAY 0.872340 (-25 3700);
PAINT GREEN (-25 3700);
DISPLAY INVISIBLE (-25 3700);
FORCEPROP 1 LAST HDL_TAP TRUE
J 2
(-350 3525);
DISPLAY 0.872340 (-350 3525);
DISPLAY INVISIBLE (-350 3525);
FORCEPROP 1 LAST PATH I86
J 2
(-23 3650);
DISPLAY 0.872340 (-23 3650);
PAINT GREEN (-23 3650);
DISPLAY INVISIBLE (-23 3650);
FORCEADD TAP..1
R 2
(-25 3750);
FORCEPROP 3 LASTPIN (25 3750) SIG_NAME M_D_CPU0_SA_DQ<28>
J 0
(35 3760);
DISPLAY 0.659574 (35 3760);
PAINT MONO (35 3760);
DISPLAY INVISIBLE (35 3760);
FORCEPROP 1 LASTPIN (25 3750) BN 28
J 2
(37 3758);
DISPLAY 0.680851 (37 3758);
PAINT GREEN (37 3758);
FORCEPROP 2 LAST CDS_LIB standard
J 0
(-25 3750);
DISPLAY INVISIBLE (-25 3750);
FORCEPROP 1 LAST BODY_TYPE PLUMBING
J 2
(-25 3800);
DISPLAY 0.872340 (-25 3800);
PAINT GREEN (-25 3800);
DISPLAY INVISIBLE (-25 3800);
FORCEPROP 1 LAST HDL_TAP TRUE
J 2
(-350 3625);
DISPLAY 0.872340 (-350 3625);
DISPLAY INVISIBLE (-350 3625);
FORCEPROP 1 LAST PATH I87
J 2
(-23 3750);
DISPLAY 0.872340 (-23 3750);
PAINT GREEN (-23 3750);
DISPLAY INVISIBLE (-23 3750);
FORCEADD TAP..1
R 2
(-25 3800);
FORCEPROP 3 LASTPIN (25 3800) SIG_NAME M_D_CPU0_SA_DQ<29>
J 0
(35 3810);
DISPLAY 0.659574 (35 3810);
PAINT MONO (35 3810);
DISPLAY INVISIBLE (35 3810);
FORCEPROP 1 LASTPIN (25 3800) BN 29
J 2
(37 3808);
DISPLAY 0.680851 (37 3808);
PAINT GREEN (37 3808);
FORCEPROP 2 LAST CDS_LIB standard
J 0
(-25 3800);
DISPLAY INVISIBLE (-25 3800);
FORCEPROP 1 LAST BODY_TYPE PLUMBING
J 2
(-25 3850);
DISPLAY 0.872340 (-25 3850);
PAINT GREEN (-25 3850);
DISPLAY INVISIBLE (-25 3850);
FORCEPROP 1 LAST HDL_TAP TRUE
J 2
(-350 3675);
DISPLAY 0.872340 (-350 3675);
DISPLAY INVISIBLE (-350 3675);
FORCEPROP 1 LAST PATH I88
J 2
(-23 3800);
DISPLAY 0.872340 (-23 3800);
PAINT GREEN (-23 3800);
DISPLAY INVISIBLE (-23 3800);
FORCEADD TAP..1
R 2
(-25 3850);
FORCEPROP 3 LASTPIN (25 3850) SIG_NAME M_D_CPU0_SA_DQ<30>
J 0
(35 3860);
DISPLAY 0.659574 (35 3860);
PAINT MONO (35 3860);
DISPLAY INVISIBLE (35 3860);
FORCEPROP 1 LASTPIN (25 3850) BN 30
J 2
(37 3858);
DISPLAY 0.680851 (37 3858);
PAINT GREEN (37 3858);
FORCEPROP 2 LAST CDS_LIB standard
J 0
(-25 3850);
DISPLAY INVISIBLE (-25 3850);
FORCEPROP 1 LAST BODY_TYPE PLUMBING
J 2
(-25 3900);
DISPLAY 0.872340 (-25 3900);
PAINT GREEN (-25 3900);
DISPLAY INVISIBLE (-25 3900);
FORCEPROP 1 LAST HDL_TAP TRUE
J 2
(-350 3725);
DISPLAY 0.872340 (-350 3725);
DISPLAY INVISIBLE (-350 3725);
FORCEPROP 1 LAST PATH I89
J 2
(-23 3850);
DISPLAY 0.872340 (-23 3850);
PAINT GREEN (-23 3850);
DISPLAY INVISIBLE (-23 3850);
FORCEADD TAP..1
R 2
(-25 50);
FORCEPROP 3 LASTPIN (25 50) SIG_NAME M_D_CPU0_SB_CB<2>
J 0
(35 60);
DISPLAY 0.659574 (35 60);
PAINT MONO (35 60);
DISPLAY INVISIBLE (35 60);
FORCEPROP 1 LASTPIN (25 50) BN 2
J 2
(37 58);
DISPLAY 0.680851 (37 58);
PAINT GREEN (37 58);
FORCEPROP 2 LAST CDS_LIB standard
J 0
(-25 50);
DISPLAY INVISIBLE (-25 50);
FORCEPROP 1 LAST BODY_TYPE PLUMBING
J 2
(-25 100);
DISPLAY 0.872340 (-25 100);
PAINT GREEN (-25 100);
DISPLAY INVISIBLE (-25 100);
FORCEPROP 1 LAST HDL_TAP TRUE
J 2
(-350 -75);
DISPLAY 0.872340 (-350 -75);
DISPLAY INVISIBLE (-350 -75);
FORCEPROP 1 LAST PATH I9
J 2
(-23 50);
DISPLAY 0.872340 (-23 50);
PAINT GREEN (-23 50);
DISPLAY INVISIBLE (-23 50);
FORCEADD TAP..1
R 2
(-25 3900);
FORCEPROP 3 LASTPIN (25 3900) SIG_NAME M_D_CPU0_SA_DQ<31>
J 0
(35 3910);
DISPLAY 0.659574 (35 3910);
PAINT MONO (35 3910);
DISPLAY INVISIBLE (35 3910);
FORCEPROP 1 LASTPIN (25 3900) BN 31
J 2
(37 3908);
DISPLAY 0.680851 (37 3908);
PAINT GREEN (37 3908);
FORCEPROP 2 LAST CDS_LIB standard
J 0
(-25 3900);
DISPLAY INVISIBLE (-25 3900);
FORCEPROP 1 LAST BODY_TYPE PLUMBING
J 2
(-25 3950);
DISPLAY 0.872340 (-25 3950);
PAINT GREEN (-25 3950);
DISPLAY INVISIBLE (-25 3950);
FORCEPROP 1 LAST HDL_TAP TRUE
J 2
(-350 3775);
DISPLAY 0.872340 (-350 3775);
DISPLAY INVISIBLE (-350 3775);
FORCEPROP 1 LAST PATH I90
J 2
(-23 3900);
DISPLAY 0.872340 (-23 3900);
PAINT GREEN (-23 3900);
DISPLAY INVISIBLE (-23 3900);
FORCEADD TAP..1
(3400 150);
FORCEPROP 3 LASTPIN (3350 150) SIG_NAME M_D_CPU0_SB_CS_N<0>
J 0
(3360 160);
DISPLAY 0.659574 (3360 160);
PAINT MONO (3360 160);
DISPLAY INVISIBLE (3360 160);
FORCEPROP 1 LASTPIN (3350 150) BN 0
J 0
(3338 158);
DISPLAY 0.680851 (3338 158);
PAINT GREEN (3338 158);
FORCEPROP 2 LAST CDS_LIB standard
J 0
(3400 150);
DISPLAY INVISIBLE (3400 150);
FORCEPROP 1 LAST BODY_TYPE PLUMBING
J 0
(3400 200);
DISPLAY 0.872340 (3400 200);
PAINT GREEN (3400 200);
DISPLAY INVISIBLE (3400 200);
FORCEPROP 1 LAST HDL_TAP TRUE
J 0
(3725 25);
DISPLAY 0.872340 (3725 25);
DISPLAY INVISIBLE (3725 25);
FORCEPROP 1 LAST PATH I92
J 0
(3398 150);
DISPLAY 0.872340 (3398 150);
PAINT GREEN (3398 150);
DISPLAY INVISIBLE (3398 150);
FORCEADD TAP..1
(3400 200);
FORCEPROP 3 LASTPIN (3350 200) SIG_NAME M_D_CPU0_SB_CS_N<1>
J 0
(3360 210);
DISPLAY 0.659574 (3360 210);
PAINT MONO (3360 210);
DISPLAY INVISIBLE (3360 210);
FORCEPROP 1 LASTPIN (3350 200) BN 1
J 0
(3338 208);
DISPLAY 0.680851 (3338 208);
PAINT GREEN (3338 208);
FORCEPROP 2 LAST CDS_LIB standard
J 0
(3400 200);
DISPLAY INVISIBLE (3400 200);
FORCEPROP 1 LAST BODY_TYPE PLUMBING
J 0
(3400 250);
DISPLAY 0.872340 (3400 250);
PAINT GREEN (3400 250);
DISPLAY INVISIBLE (3400 250);
FORCEPROP 1 LAST HDL_TAP TRUE
J 0
(3725 75);
DISPLAY 0.872340 (3725 75);
DISPLAY INVISIBLE (3725 75);
FORCEPROP 1 LAST PATH I93
J 0
(3398 200);
DISPLAY 0.872340 (3398 200);
PAINT GREEN (3398 200);
DISPLAY INVISIBLE (3398 200);
FORCEADD TAP..1
(3400 250);
FORCEPROP 3 LASTPIN (3350 250) SIG_NAME M_D_CPU0_SB_CS_N<2>
J 0
(3360 260);
DISPLAY 0.659574 (3360 260);
PAINT MONO (3360 260);
DISPLAY INVISIBLE (3360 260);
FORCEPROP 1 LASTPIN (3350 250) BN 2
J 0
(3338 258);
DISPLAY 0.680851 (3338 258);
PAINT GREEN (3338 258);
FORCEPROP 2 LAST CDS_LIB standard
J 0
(3400 250);
DISPLAY INVISIBLE (3400 250);
FORCEPROP 1 LAST BODY_TYPE PLUMBING
J 0
(3400 300);
DISPLAY 0.872340 (3400 300);
PAINT GREEN (3400 300);
DISPLAY INVISIBLE (3400 300);
FORCEPROP 1 LAST HDL_TAP TRUE
J 0
(3725 125);
DISPLAY 0.872340 (3725 125);
DISPLAY INVISIBLE (3725 125);
FORCEPROP 1 LAST PATH I94
J 0
(3398 250);
DISPLAY 0.872340 (3398 250);
PAINT GREEN (3398 250);
DISPLAY INVISIBLE (3398 250);
FORCEADD OFFPAGE..4
(4500 -300);
FORCEPROP 2 LAST $XR1 89 
J 0
(4776 -300);
DISPLAY 0.638298 (4776 -300);
PAINT MONO (4776 -300);
FORCEPROP 2 LAST $XR0 88 
J 0
(4686 -300);
DISPLAY 0.638298 (4686 -300);
PAINT MONO (4686 -300);
FORCEPROP 2 LAST CDS_LIB standard
J 0
(4500 -300);
PAINT MONO (4500 -300);
DISPLAY INVISIBLE (4500 -300);
FORCEPROP 1 LAST OFFPAGE TRUE
J 0
(4825 -425);
DISPLAY 1.170213 (4825 -425);
PAINT GREEN (4825 -425);
DISPLAY INVISIBLE (4825 -425);
FORCEPROP 1 LAST COMMENT_BODY TRUE
J 0
(4475 -400);
DISPLAY 1.170213 (4475 -400);
PAINT GREEN (4475 -400);
DISPLAY INVISIBLE (4475 -400);
FORCEPROP 2 LAST PATH I95
J 0
(4675 -225);
DISPLAY 1.021277 (4675 -225);
DISPLAY INVISIBLE (4675 -225);
FORCEADD OFFPAGE..4
(4500 0);
FORCEPROP 2 LAST $XR0 89 
J 0
(4686 0);
DISPLAY 0.638298 (4686 0);
PAINT MONO (4686 0);
FORCEPROP 2 LAST CDS_LIB standard
J 0
(4500 0);
PAINT MONO (4500 0);
DISPLAY INVISIBLE (4500 0);
FORCEPROP 1 LAST OFFPAGE TRUE
J 0
(4825 -125);
DISPLAY 1.170213 (4825 -125);
PAINT GREEN (4825 -125);
DISPLAY INVISIBLE (4825 -125);
FORCEPROP 1 LAST COMMENT_BODY TRUE
J 0
(4475 -100);
DISPLAY 1.170213 (4475 -100);
PAINT GREEN (4475 -100);
DISPLAY INVISIBLE (4475 -100);
FORCEPROP 2 LAST PATH I96
J 0
(4675 75);
DISPLAY 1.021277 (4675 75);
DISPLAY INVISIBLE (4675 75);
FORCEADD OFFPAGE..4
(4500 -50);
FORCEPROP 2 LAST $XR0 88 
J 0
(4686 -50);
DISPLAY 0.638298 (4686 -50);
PAINT MONO (4686 -50);
FORCEPROP 2 LAST CDS_LIB standard
J 0
(4500 -50);
PAINT MONO (4500 -50);
DISPLAY INVISIBLE (4500 -50);
FORCEPROP 1 LAST OFFPAGE TRUE
J 0
(4825 -175);
DISPLAY 1.170213 (4825 -175);
PAINT GREEN (4825 -175);
DISPLAY INVISIBLE (4825 -175);
FORCEPROP 1 LAST COMMENT_BODY TRUE
J 0
(4475 -150);
DISPLAY 1.170213 (4475 -150);
PAINT GREEN (4475 -150);
DISPLAY INVISIBLE (4475 -150);
FORCEPROP 2 LAST PATH I97
J 0
(4675 25);
DISPLAY 1.021277 (4675 25);
DISPLAY INVISIBLE (4675 25);
FORCEADD OFFPAGE..4
(4500 -150);
FORCEPROP 2 LAST $XR0 89 
J 0
(4686 -150);
DISPLAY 0.638298 (4686 -150);
PAINT MONO (4686 -150);
FORCEPROP 2 LAST CDS_LIB standard
J 0
(4500 -150);
PAINT MONO (4500 -150);
DISPLAY INVISIBLE (4500 -150);
FORCEPROP 1 LAST OFFPAGE TRUE
J 0
(4825 -275);
DISPLAY 1.170213 (4825 -275);
PAINT GREEN (4825 -275);
DISPLAY INVISIBLE (4825 -275);
FORCEPROP 1 LAST COMMENT_BODY TRUE
J 0
(4475 -250);
DISPLAY 1.170213 (4475 -250);
PAINT GREEN (4475 -250);
DISPLAY INVISIBLE (4475 -250);
FORCEPROP 2 LAST PATH I98
J 0
(4675 -75);
DISPLAY 1.021277 (4675 -75);
DISPLAY INVISIBLE (4675 -75);
FORCEADD OFFPAGE..4
(4500 -200);
FORCEPROP 2 LAST $XR0 88 
J 0
(4686 -200);
DISPLAY 0.638298 (4686 -200);
PAINT MONO (4686 -200);
FORCEPROP 2 LAST CDS_LIB standard
J 0
(4500 -200);
PAINT MONO (4500 -200);
DISPLAY INVISIBLE (4500 -200);
FORCEPROP 1 LAST OFFPAGE TRUE
J 0
(4825 -325);
DISPLAY 1.170213 (4825 -325);
PAINT GREEN (4825 -325);
DISPLAY INVISIBLE (4825 -325);
FORCEPROP 1 LAST COMMENT_BODY TRUE
J 0
(4475 -300);
DISPLAY 1.170213 (4475 -300);
PAINT GREEN (4475 -300);
DISPLAY INVISIBLE (4475 -300);
FORCEPROP 2 LAST PATH I99
J 0
(4675 -125);
DISPLAY 1.021277 (4675 -125);
DISPLAY INVISIBLE (4675 -125);
FORCEADD QUANTA_TITLE_BLOCK_C..1
(6325 -1600);
FORCEPROP 0 LAST CDS_CON_LAST_MODIFIED Fri Aug 25 14:00:08 2023
J 0
(4440 -1585);
PAINT MONO (4440 -1585);
DISPLAY INVISIBLE (4440 -1585);
FORCEPROP 1 LAST CUSTOM_TXT_CDS <CON_LAST_MODIFIED>
J 0
(4440 -1585);
DISPLAY 0.978723 (4440 -1585);
FORCEPROP 2 LAST CUSTOM_TXT_CDS <XR_PAGE_TITLE>
J 0
(-1565 3650);
DISPLAY 0.638298 (-1565 3650);
PAINT PINK (-1565 3650);
DISPLAY INVISIBLE (-1565 3650);
FORCEPROP 2 LAST CUSTOM_TXT_CDS <Q_NUMBER>
J 0
(4922 -1497);
DISPLAY 1.212766 (4922 -1497);
FORCEPROP 2 LAST CUSTOM_TXT_CDS 01
J 0
(6141 -1497);
DISPLAY 1.212766 (6141 -1497);
FORCEPROP 1 LAST CUSTOM_TXT_CDS <NAME_2>
J 0
(3150 -1550);
FORCEPROP 1 LAST CUSTOM_TXT_CDS <NAME_1>
J 0
(3150 -1425);
FORCEPROP 1 LAST CUSTOM_TXT_CDS <Q_PROJ>
J 0
(3943 -1498);
DISPLAY 1.212766 (3943 -1498);
FORCEPROP 1 LAST CUSTOM_TXT_CDS <Q_REV>
J 0
(6141 -1497);
DISPLAY 1.212766 (6141 -1497);
FORCEPROP 1 LAST CUSTOM_TXT_CDS <CON_PAGE_NUM> OF <CON_TOTAL_PAGES>
J 0
(5879 -1582);
DISPLAY 0.978723 (5879 -1582);
FORCEPROP 1 LAST Q_TITLE SPR CPU0 - DDR CH D (11 OF 30)
J 0
(-3041 -1574);
DISPLAY 1.957447 (-3041 -1574);
PAINT GREEN (-3041 -1574);
FORCEPROP 1 LAST Q_DEPT 
J 1
(2562 -1551);
DISPLAY 1.957447 (2562 -1551);
PAINT GREEN (2562 -1551);
FORCEPROP 2 LAST PAGE_BORDER TRUE
J 0
(-1565 3650);
DISPLAY 0.638298 (-1565 3650);
PAINT PINK (-1565 3650);
DISPLAY INVISIBLE (-1565 3650);
FORCEPROP 1 LAST CDS_LMAN_SYM_OUTLINE -9475,6775,100,-125
J 0
(6325 -1600);
DISPLAY 0.468085 (6325 -1600);
PAINT GREEN (6325 -1600);
DISPLAY INVISIBLE (6325 -1600);
FORCEPROP 2 LAST CDS_LIB pure_quanta
J 0
(6325 -1600);
PAINT MONO (6325 -1600);
DISPLAY INVISIBLE (6325 -1600);
FORCEPROP 2 LAST CDS_XR_PAGE_TITLE CR-23 : @S9S_MB_2U_LIB.S9S_MB_2U(SCH_1):PAGE23
J 0
(-1565 3650);
DISPLAY 0.638298 (-1565 3650);
PAINT PINK (-1565 3650);
DISPLAY INVISIBLE (-1565 3650);
FORCEPROP 1 LAST COMMENT_BODY TRUE
J 0
(6337 -1613);
DISPLAY 0.978723 (6337 -1613);
PAINT GREEN (6337 -1613);
DISPLAY INVISIBLE (6337 -1613);
WIRE 17 -1 (3450 1575)(3450 1625);
WIRE 17 -1 (3450 1525)(3450 1575);
WIRE 17 -1 (3450 1625)(4450 1625);
FORCEPROP 2 LAST SIG_NAME M_D_CPU0_SA_CA<6:0>
J 0
(3590 1635);
DISPLAY 0.680851 (3590 1635);
PAINT WHITE (3590 1635);
WIRE 17 -1 (3450 1475)(3450 1525);
WIRE 17 -1 (3450 1425)(3450 1475);
WIRE 17 -1 (3450 1375)(3450 1425);
WIRE 17 -1 (3450 1325)(3450 1375);
WIRE 17 -1 (3450 575)(3450 625);
WIRE 17 -1 (3450 525)(3450 575);
WIRE 17 -1 (3450 625)(4450 625);
FORCEPROP 2 LAST SIG_NAME M_D_CPU0_SA_CS_N<3:0>
J 0
(3590 635);
DISPLAY 0.680851 (3590 635);
PAINT WHITE (3590 635);
WIRE 17 -1 (3450 475)(3450 525);
WIRE 17 -1 (3450 3325)(3450 3375);
WIRE 17 -1 (3450 3275)(3450 3325);
WIRE 17 -1 (3450 3375)(4450 3375);
FORCEPROP 2 LAST SIG_NAME M_D_CPU0_SA_DQS_DN<9:0>
J 0
(3590 3385);
DISPLAY 0.680851 (3590 3385);
PAINT WHITE (3590 3385);
WIRE 17 -1 (3450 3225)(3450 3275);
WIRE 17 -1 (3450 3175)(3450 3225);
WIRE 17 -1 (3450 3125)(3450 3175);
WIRE 17 -1 (3450 3075)(3450 3125);
WIRE 17 -1 (3450 3025)(3450 3075);
WIRE 17 -1 (3450 2975)(3450 3025);
WIRE 17 -1 (3450 2925)(3450 2975);
WIRE 17 -1 (3450 3875)(3450 3925);
WIRE 17 -1 (3450 3825)(3450 3875);
WIRE 17 -1 (3450 3925)(4450 3925);
FORCEPROP 2 LAST SIG_NAME M_D_CPU0_SA_DQS_DP<9:0>
J 0
(3590 3935);
DISPLAY 0.680851 (3590 3935);
PAINT WHITE (3590 3935);
WIRE 17 -1 (3450 3775)(3450 3825);
WIRE 17 -1 (3450 3725)(3450 3775);
WIRE 17 -1 (3450 3675)(3450 3725);
WIRE 17 -1 (3450 3625)(3450 3675);
WIRE 17 -1 (3450 3575)(3450 3625);
WIRE 17 -1 (3450 3525)(3450 3575);
WIRE 17 -1 (3450 3475)(3450 3525);
WIRE 17 -1 (3450 1075)(3450 1125);
WIRE 17 -1 (3450 1025)(3450 1075);
WIRE 17 -1 (3450 1125)(4450 1125);
FORCEPROP 2 LAST SIG_NAME M_D_CPU0_SB_CA<6:0>
J 0
(3590 1135);
DISPLAY 0.680851 (3590 1135);
PAINT WHITE (3590 1135);
WIRE 17 -1 (3450 975)(3450 1025);
WIRE 17 -1 (3450 925)(3450 975);
WIRE 17 -1 (3450 875)(3450 925);
WIRE 17 -1 (3450 825)(3450 875);
WIRE 17 -1 (3450 275)(3450 325);
WIRE 17 -1 (3450 225)(3450 275);
WIRE 17 -1 (3450 325)(4450 325);
FORCEPROP 2 LAST SIG_NAME M_D_CPU0_SB_CS_N<3:0>
J 0
(3590 335);
DISPLAY 0.680851 (3590 335);
PAINT WHITE (3590 335);
WIRE 17 -1 (3450 175)(3450 225);
WIRE 17 -1 (3450 2175)(3450 2225);
WIRE 17 -1 (3450 2125)(3450 2175);
WIRE 17 -1 (3450 2225)(4450 2225);
FORCEPROP 2 LAST SIG_NAME M_D_CPU0_SB_DQS_DN<9:0>
J 0
(3590 2235);
DISPLAY 0.680851 (3590 2235);
PAINT WHITE (3590 2235);
WIRE 17 -1 (3450 2075)(3450 2125);
WIRE 17 -1 (3450 2025)(3450 2075);
WIRE 17 -1 (3450 1975)(3450 2025);
WIRE 17 -1 (3450 1925)(3450 1975);
WIRE 17 -1 (3450 1875)(3450 1925);
WIRE 17 -1 (3450 1825)(3450 1875);
WIRE 17 -1 (3450 1775)(3450 1825);
WIRE 17 -1 (3450 2725)(3450 2775);
WIRE 17 -1 (3450 2675)(3450 2725);
WIRE 17 -1 (3450 2775)(4450 2775);
FORCEPROP 2 LAST SIG_NAME M_D_CPU0_SB_DQS_DP<9:0>
J 0
(3590 2785);
DISPLAY 0.680851 (3590 2785);
PAINT WHITE (3590 2785);
WIRE 17 -1 (3450 2625)(3450 2675);
WIRE 17 -1 (3450 2575)(3450 2625);
WIRE 17 -1 (3450 2525)(3450 2575);
WIRE 17 -1 (3450 2475)(3450 2525);
WIRE 17 -1 (3450 2425)(3450 2475);
WIRE 17 -1 (3450 2375)(3450 2425);
WIRE 17 -1 (3450 2325)(3450 2375);
WIRE 17 -1 (-75 -25)(-75 25);
WIRE 17 -1 (-75 25)(-75 75);
WIRE 17 -1 (-75 75)(-75 125);
WIRE 17 -1 (-75 125)(-75 175);
WIRE 17 -1 (-75 175)(-75 225);
WIRE 17 -1 (-75 225)(-75 275);
WIRE 17 -1 (-75 275)(-75 325);
WIRE 17 -1 (-1000 325)(-75 325);
FORCEPROP 2 LAST SIG_NAME M_D_CPU0_SB_CB<7:0>
J 0
(-860 335);
DISPLAY 0.680851 (-860 335);
PAINT WHITE (-860 335);
WIRE 17 -1 (-75 375)(-75 425);
WIRE 17 -1 (-75 425)(-75 475);
WIRE 17 -1 (-75 475)(-75 525);
WIRE 17 -1 (-75 525)(-75 575);
WIRE 17 -1 (-75 575)(-75 625);
WIRE 17 -1 (-75 625)(-75 675);
WIRE 17 -1 (-75 675)(-75 725);
WIRE 17 -1 (-75 725)(-75 775);
WIRE 17 -1 (-75 775)(-75 825);
WIRE 17 -1 (-75 825)(-75 875);
WIRE 17 -1 (-75 875)(-75 925);
WIRE 17 -1 (-75 925)(-75 975);
WIRE 17 -1 (-75 975)(-75 1025);
WIRE 17 -1 (-75 1025)(-75 1075);
WIRE 17 -1 (-75 1075)(-75 1125);
WIRE 17 -1 (-75 1125)(-75 1175);
WIRE 17 -1 (-75 1175)(-75 1225);
WIRE 17 -1 (-75 1225)(-75 1275);
WIRE 17 -1 (-75 1275)(-75 1325);
WIRE 17 -1 (-75 1325)(-75 1375);
WIRE 17 -1 (-75 1375)(-75 1425);
WIRE 17 -1 (-75 1425)(-75 1475);
WIRE 17 -1 (-75 1475)(-75 1525);
WIRE 17 -1 (-75 1525)(-75 1575);
WIRE 17 -1 (-75 1575)(-75 1625);
WIRE 17 -1 (-75 1625)(-75 1675);
WIRE 17 -1 (-75 1675)(-75 1725);
WIRE 17 -1 (-75 1725)(-75 1775);
WIRE 17 -1 (-75 1775)(-75 1825);
WIRE 17 -1 (-75 1825)(-75 1875);
WIRE 17 -1 (-75 1875)(-75 1925);
WIRE 17 -1 (-1000 1925)(-75 1925);
FORCEPROP 2 LAST SIG_NAME M_D_CPU0_SB_DQ<31:0>
J 0
(-860 1935);
DISPLAY 0.680851 (-860 1935);
PAINT WHITE (-860 1935);
WIRE 17 -1 (-75 1975)(-75 2025);
WIRE 17 -1 (-75 2025)(-75 2075);
WIRE 17 -1 (-75 2075)(-75 2125);
WIRE 17 -1 (-75 2125)(-75 2175);
WIRE 17 -1 (-75 2175)(-75 2225);
WIRE 17 -1 (-75 2225)(-75 2275);
WIRE 17 -1 (-75 2275)(-75 2325);
WIRE 17 -1 (-1000 2325)(-75 2325);
FORCEPROP 2 LAST SIG_NAME M_D_CPU0_SA_CB<7:0>
J 0
(-860 2335);
DISPLAY 0.680851 (-860 2335);
PAINT WHITE (-860 2335);
WIRE 17 -1 (-75 2375)(-75 2425);
WIRE 17 -1 (-75 2425)(-75 2475);
WIRE 17 -1 (-75 2475)(-75 2525);
WIRE 17 -1 (-75 2525)(-75 2575);
WIRE 17 -1 (-75 2575)(-75 2625);
WIRE 17 -1 (-75 2625)(-75 2675);
WIRE 17 -1 (-75 2675)(-75 2725);
WIRE 17 -1 (-75 2725)(-75 2775);
WIRE 17 -1 (-75 2775)(-75 2825);
WIRE 17 -1 (-75 2825)(-75 2875);
WIRE 17 -1 (-75 2875)(-75 2925);
WIRE 17 -1 (-75 2925)(-75 2975);
WIRE 17 -1 (-75 2975)(-75 3025);
WIRE 17 -1 (-75 3025)(-75 3075);
WIRE 17 -1 (-75 3075)(-75 3125);
WIRE 17 -1 (-75 3125)(-75 3175);
WIRE 17 -1 (-75 3175)(-75 3225);
WIRE 17 -1 (-75 3225)(-75 3275);
WIRE 17 -1 (-75 3275)(-75 3325);
WIRE 17 -1 (-75 3325)(-75 3375);
WIRE 17 -1 (-75 3375)(-75 3425);
WIRE 17 -1 (-75 3425)(-75 3475);
WIRE 17 -1 (-75 3475)(-75 3525);
WIRE 17 -1 (-75 3525)(-75 3575);
WIRE 17 -1 (-75 3575)(-75 3625);
WIRE 17 -1 (-75 3625)(-75 3675);
WIRE 17 -1 (-75 3675)(-75 3725);
WIRE 17 -1 (-75 3725)(-75 3775);
WIRE 17 -1 (-75 3775)(-75 3825);
WIRE 17 -1 (-75 3825)(-75 3875);
WIRE 17 -1 (-75 3875)(-75 3925);
WIRE 17 -1 (-1000 3925)(-75 3925);
FORCEPROP 2 LAST SIG_NAME M_D_CPU0_SA_DQ<31:0>
J 0
(-860 3935);
DISPLAY 0.680851 (-860 3935);
PAINT WHITE (-860 3935);
WIRE 17 -1 (-75 -175)(-75 -125);
WIRE 17 -1 (-1000 -125)(-75 -125);
FORCEPROP 2 LAST SIG_NAME M_D_CPU0_CLK_DP<1:0>
J 0
(-860 -115);
DISPLAY 0.680851 (-860 -115);
PAINT WHITE (-860 -115);
WIRE 17 -1 (-75 -275)(-75 -225);
WIRE 17 -1 (-1000 -225)(-75 -225);
FORCEPROP 2 LAST SIG_NAME M_D_CPU0_CLK_DN<1:0>
J 0
(-860 -215);
DISPLAY 0.680851 (-860 -215);
PAINT WHITE (-860 -215);
WIRE 16 -1 (25 -250)(475 -250);
WIRE 16 -1 (25 -300)(475 -300);
WIRE 16 -1 (25 -150)(475 -150);
WIRE 16 -1 (25 -200)(475 -200);
WIRE 16 -1 (25 3900)(475 3900);
WIRE 16 -1 (25 3850)(475 3850);
WIRE 16 -1 (25 3800)(475 3800);
WIRE 16 -1 (25 3750)(475 3750);
WIRE 16 -1 (25 3700)(475 3700);
WIRE 16 -1 (25 3650)(475 3650);
WIRE 16 -1 (25 3600)(475 3600);
WIRE 16 -1 (25 3550)(475 3550);
WIRE 16 -1 (25 3500)(475 3500);
WIRE 16 -1 (25 3450)(475 3450);
WIRE 16 -1 (25 3400)(475 3400);
WIRE 16 -1 (25 3350)(475 3350);
WIRE 16 -1 (25 3300)(475 3300);
WIRE 16 -1 (25 3250)(475 3250);
WIRE 16 -1 (25 3200)(475 3200);
WIRE 16 -1 (25 3150)(475 3150);
WIRE 16 -1 (25 3100)(475 3100);
WIRE 16 -1 (25 3050)(475 3050);
WIRE 16 -1 (25 3000)(475 3000);
WIRE 16 -1 (25 2950)(475 2950);
WIRE 16 -1 (25 2900)(475 2900);
WIRE 16 -1 (25 2850)(475 2850);
WIRE 16 -1 (25 2800)(475 2800);
WIRE 16 -1 (25 2750)(475 2750);
WIRE 16 -1 (25 2700)(475 2700);
WIRE 16 -1 (25 2650)(475 2650);
WIRE 16 -1 (25 2600)(475 2600);
WIRE 16 -1 (25 2550)(475 2550);
WIRE 16 -1 (25 2500)(475 2500);
WIRE 16 -1 (25 2450)(475 2450);
WIRE 16 -1 (25 2400)(475 2400);
WIRE 16 -1 (25 2350)(475 2350);
WIRE 16 -1 (25 2300)(475 2300);
WIRE 16 -1 (25 2250)(475 2250);
WIRE 16 -1 (25 2200)(475 2200);
WIRE 16 -1 (25 2150)(475 2150);
WIRE 16 -1 (25 2100)(475 2100);
WIRE 16 -1 (25 2050)(475 2050);
WIRE 16 -1 (25 2000)(475 2000);
WIRE 16 -1 (25 1950)(475 1950);
WIRE 16 -1 (25 1900)(475 1900);
WIRE 16 -1 (25 1850)(475 1850);
WIRE 16 -1 (25 1800)(475 1800);
WIRE 16 -1 (25 1750)(475 1750);
WIRE 16 -1 (25 1700)(475 1700);
WIRE 16 -1 (25 1650)(475 1650);
WIRE 16 -1 (25 1600)(475 1600);
WIRE 16 -1 (25 1550)(475 1550);
WIRE 16 -1 (25 1500)(475 1500);
WIRE 16 -1 (25 1450)(475 1450);
WIRE 16 -1 (25 1400)(475 1400);
WIRE 16 -1 (25 1350)(475 1350);
WIRE 16 -1 (25 1300)(475 1300);
WIRE 16 -1 (25 1250)(475 1250);
WIRE 16 -1 (25 1200)(475 1200);
WIRE 16 -1 (25 1150)(475 1150);
WIRE 16 -1 (25 1100)(475 1100);
WIRE 16 -1 (25 1050)(475 1050);
WIRE 16 -1 (25 1000)(475 1000);
WIRE 16 -1 (25 950)(475 950);
WIRE 16 -1 (25 900)(475 900);
WIRE 16 -1 (25 850)(475 850);
WIRE 16 -1 (25 800)(475 800);
WIRE 16 -1 (25 750)(475 750);
WIRE 16 -1 (25 700)(475 700);
WIRE 16 -1 (25 650)(475 650);
WIRE 16 -1 (25 600)(475 600);
WIRE 16 -1 (25 550)(475 550);
WIRE 16 -1 (25 500)(475 500);
WIRE 16 -1 (25 450)(475 450);
WIRE 16 -1 (25 400)(475 400);
WIRE 16 -1 (25 350)(475 350);
WIRE 16 -1 (25 300)(475 300);
WIRE 16 -1 (25 250)(475 250);
WIRE 16 -1 (25 200)(475 200);
WIRE 16 -1 (25 150)(475 150);
WIRE 16 -1 (25 100)(475 100);
WIRE 16 -1 (25 50)(475 50);
WIRE 16 -1 (25 0)(475 0);
WIRE 16 -1 (25 -50)(475 -50);
WIRE 16 -1 (4450 750)(2925 750);
FORCEPROP 2 LAST SIG_NAME M_D_CPU0_SB_PAR
J 0
(3559 759);
DISPLAY 0.680851 (3559 759);
PAINT WHITE (3559 759);
WIRE 16 -1 (2925 2300)(3350 2300);
WIRE 16 -1 (2925 2350)(3350 2350);
WIRE 16 -1 (2925 2400)(3350 2400);
WIRE 16 -1 (2925 2450)(3350 2450);
WIRE 16 -1 (2925 2500)(3350 2500);
WIRE 16 -1 (2925 2550)(3350 2550);
WIRE 16 -1 (2925 2600)(3350 2600);
WIRE 16 -1 (2925 2650)(3350 2650);
WIRE 16 -1 (2925 2700)(3350 2700);
WIRE 16 -1 (2925 2750)(3350 2750);
WIRE 16 -1 (2925 1750)(3350 1750);
WIRE 16 -1 (2925 1800)(3350 1800);
WIRE 16 -1 (2925 1850)(3350 1850);
WIRE 16 -1 (2925 1900)(3350 1900);
WIRE 16 -1 (2925 1950)(3350 1950);
WIRE 16 -1 (2925 2000)(3350 2000);
WIRE 16 -1 (2925 2050)(3350 2050);
WIRE 16 -1 (2925 2100)(3350 2100);
WIRE 16 -1 (2925 2150)(3350 2150);
WIRE 16 -1 (2925 2200)(3350 2200);
WIRE 16 -1 (2925 150)(3350 150);
WIRE 16 -1 (2925 200)(3350 200);
WIRE 16 -1 (2925 250)(3350 250);
WIRE 16 -1 (2925 300)(3350 300);
WIRE 16 -1 (2925 800)(3350 800);
WIRE 16 -1 (2925 850)(3350 850);
WIRE 16 -1 (2925 900)(3350 900);
WIRE 16 -1 (2925 950)(3350 950);
WIRE 16 -1 (2925 1000)(3350 1000);
WIRE 16 -1 (2925 1050)(3350 1050);
WIRE 16 -1 (2925 1100)(3350 1100);
WIRE 16 -1 (4450 1250)(2925 1250);
FORCEPROP 2 LAST SIG_NAME M_D_CPU0_SA_PAR
J 0
(3559 1259);
DISPLAY 0.680851 (3559 1259);
PAINT WHITE (3559 1259);
WIRE 16 -1 (2925 3450)(3350 3450);
WIRE 16 -1 (2925 3500)(3350 3500);
WIRE 16 -1 (2925 3550)(3350 3550);
WIRE 16 -1 (2925 3600)(3350 3600);
WIRE 16 -1 (2925 3650)(3350 3650);
WIRE 16 -1 (2925 3700)(3350 3700);
WIRE 16 -1 (2925 3750)(3350 3750);
WIRE 16 -1 (2925 3800)(3350 3800);
WIRE 16 -1 (2925 3850)(3350 3850);
WIRE 16 -1 (2925 3900)(3350 3900);
WIRE 16 -1 (2925 2900)(3350 2900);
WIRE 16 -1 (2925 2950)(3350 2950);
WIRE 16 -1 (2925 3000)(3350 3000);
WIRE 16 -1 (2925 3050)(3350 3050);
WIRE 16 -1 (2925 3100)(3350 3100);
WIRE 16 -1 (2925 3150)(3350 3150);
WIRE 16 -1 (2925 3200)(3350 3200);
WIRE 16 -1 (2925 3250)(3350 3250);
WIRE 16 -1 (2925 3300)(3350 3300);
WIRE 16 -1 (2925 3350)(3350 3350);
WIRE 16 -1 (2925 450)(3350 450);
WIRE 16 -1 (2925 500)(3350 500);
WIRE 16 -1 (2925 550)(3350 550);
WIRE 16 -1 (2925 600)(3350 600);
WIRE 16 -1 (2925 1300)(3350 1300);
WIRE 16 -1 (2925 1350)(3350 1350);
WIRE 16 -1 (2925 1400)(3350 1400);
WIRE 16 -1 (2925 1450)(3350 1450);
WIRE 16 -1 (2925 1500)(3350 1500);
WIRE 16 -1 (2925 1550)(3350 1550);
WIRE 16 -1 (2925 1600)(3350 1600);
WIRE 16 -1 (4450 -200)(2925 -200);
FORCEPROP 2 LAST SIG_NAME M_D_CPU0_SB_RSP<0>
J 0
(3559 -191);
DISPLAY 0.680851 (3559 -191);
PAINT WHITE (3559 -191);
WIRE 16 -1 (4450 -150)(2925 -150);
FORCEPROP 2 LAST SIG_NAME M_D_CPU0_SB_RSP<1>
J 0
(3559 -141);
DISPLAY 0.680851 (3559 -141);
PAINT WHITE (3559 -141);
WIRE 16 -1 (4450 -50)(2925 -50);
FORCEPROP 2 LAST SIG_NAME M_D_CPU0_SA_RSP<0>
J 0
(3559 -41);
DISPLAY 0.680851 (3559 -41);
PAINT WHITE (3559 -41);
WIRE 16 -1 (4450 0)(2925 0);
FORCEPROP 2 LAST SIG_NAME M_D_CPU0_SA_RSP<1>
J 0
(3559 9);
DISPLAY 0.680851 (3559 9);
PAINT WHITE (3559 9);
WIRE 16 -1 (4450 -300)(2925 -300);
FORCEPROP 2 LAST SIG_NAME M_D_CPU0_ALERT_N
J 0
(3559 -291);
DISPLAY 0.680851 (3559 -291);
PAINT WHITE (3559 -291);
QUIT
